G04 ================== begin FILE IDENTIFICATION RECORD ==================*
G04 Layout Name:  12433-1M.brd*
G04 Film Name:    TSMD*
G04 File Format:  Gerber RS274X*
G04 File Origin:  Cadence Allegro 16.2-S037*
G04 Origin Date:  Fri Dec 07 18:55:07 2012*
G04 *
G04 Layer:  VIA CLASS/PASTEMASK_TOP*
G04 Layer:  PIN/PASTEMASK_TOP*
G04 Layer:  PACKAGE GEOMETRY/PASTEMASK_TOP*
G04 Layer:  DRAWING FORMAT/LAYER_PCB_STORY*
G04 Layer:  DRAWING FORMAT/LAYER_PAST_T*
G04 Layer:  BOARD GEOMETRY/PANEL_OUTLINE*
G04 *
G04 Offset:    (0.00 0.00)*
G04 Mirror:    No*
G04 Mode:      Positive*
G04 Rotation:  0*
G04 FullContactRelief:  No*
G04 UndefLineWidth:     6.00*
G04 ================== end FILE IDENTIFICATION RECORD ====================*
%FSLAX35Y35*MOIN*%
%IR0*IPPOS*OFA0.00000B0.00000*MIA0B0*SFA1.00000B1.00000*%
%AMMACRO38*
4,1,40,.013,.017,
-.013,.017,
-.013695,.016939,
-.014368,.016759,
-.015,.016464,
-.015571,.016064,
-.016064,.015571,
-.016464,.015,
-.016759,.014368,
-.016939,.013695,
-.017,.013,
-.017,-.013,
-.016939,-.013695,
-.016759,-.014368,
-.016464,-.015,
-.016064,-.015571,
-.015571,-.016064,
-.015,-.016464,
-.014368,-.016759,
-.013695,-.016939,
-.013,-.017,
.013,-.017,
.013695,-.016939,
.014368,-.016759,
.015,-.016464,
.015571,-.016064,
.016064,-.015571,
.016464,-.015,
.016759,-.014368,
.016939,-.013695,
.017,-.013,
.017,.013,
.016939,.013695,
.016759,.014368,
.016464,.015,
.016064,.015571,
.015571,.016064,
.015,.016464,
.014368,.016759,
.013695,.016939,
.013,.017,
0.0*
%
%ADD38MACRO38*%
%AMMACRO20*
4,1,40,.017,-.013,
.017,.013,
.016939,.013695,
.016759,.014368,
.016464,.015,
.016064,.015571,
.015571,.016064,
.015,.016464,
.014368,.016759,
.013695,.016939,
.013,.017,
-.013,.017,
-.013695,.016939,
-.014368,.016759,
-.015,.016464,
-.015571,.016064,
-.016064,.015571,
-.016464,.015,
-.016759,.014368,
-.016939,.013695,
-.017,.013,
-.017,-.013,
-.016939,-.013695,
-.016759,-.014368,
-.016464,-.015,
-.016064,-.015571,
-.015571,-.016064,
-.015,-.016464,
-.014368,-.016759,
-.013695,-.016939,
-.013,-.017,
.013,-.017,
.013695,-.016939,
.014368,-.016759,
.015,-.016464,
.015571,-.016064,
.016064,-.015571,
.016464,-.015,
.016759,-.014368,
.016939,-.013695,
.017,-.013,
0.0*
%
%ADD20MACRO20*%
%ADD24R,.08X.127*%
%ADD39R,.085X.128*%
%ADD44R,.208X.087*%
%ADD29R,.087X.208*%
%ADD11R,.05X.05*%
%AMMACRO69*
4,1,40,-.014,-.008,
-.014,.008,
-.013939,.008695,
-.013759,.009368,
-.013464,.01,
-.013064,.010571,
-.012571,.011064,
-.012,.011464,
-.011368,.011759,
-.010695,.011939,
-.01,.012,
.01,.012,
.010695,.011939,
.011368,.011759,
.012,.011464,
.012571,.011064,
.013064,.010571,
.013464,.01,
.013759,.009368,
.013939,.008695,
.014,.008,
.014,-.008,
.013939,-.008695,
.013759,-.009368,
.013464,-.01,
.013064,-.010571,
.012571,-.011064,
.012,-.011464,
.011368,-.011759,
.010695,-.011939,
.01,-.012,
-.01,-.012,
-.010695,-.011939,
-.011368,-.011759,
-.012,-.011464,
-.012571,-.011064,
-.013064,-.010571,
-.013464,-.01,
-.013759,-.009368,
-.013939,-.008695,
-.014,-.008,
0.0*
%
%ADD69MACRO69*%
%AMMACRO64*
4,1,40,-.007,-.0225,
-.008389,-.022378,
-.009736,-.022018,
-.011,-.021428,
-.012142,-.020628,
-.013128,-.019642,
-.013928,-.0185,
-.014518,-.017236,
-.014878,-.015889,
-.015,-.0145,
-.015,.0145,
-.014878,.015889,
-.014518,.017236,
-.013928,.0185,
-.013128,.019642,
-.012142,.020628,
-.011,.021428,
-.009736,.022018,
-.008389,.022378,
-.007,.0225,
.007,.0225,
.008389,.022378,
.009736,.022018,
.011,.021428,
.012142,.020628,
.013128,.019642,
.013928,.0185,
.014518,.017236,
.014878,.015889,
.015,.0145,
.015,-.0145,
.014878,-.015889,
.014518,-.017236,
.013928,-.0185,
.013128,-.019642,
.012142,-.020628,
.011,-.021428,
.009736,-.022018,
.008389,-.022378,
.007,-.0225,
-.007,-.0225,
0.0*
%
%ADD64MACRO64*%
%AMMACRO32*
4,1,40,.011,-.007,
.011,.007,
.010939,.007695,
.010759,.008368,
.010464,.009,
.010064,.009571,
.009571,.010064,
.009,.010464,
.008368,.010759,
.007695,.010939,
.007,.011,
-.007,.011,
-.007695,.010939,
-.008368,.010759,
-.009,.010464,
-.009571,.010064,
-.010064,.009571,
-.010464,.009,
-.010759,.008368,
-.010939,.007695,
-.011,.007,
-.011,-.007,
-.010939,-.007695,
-.010759,-.008368,
-.010464,-.009,
-.010064,-.009571,
-.009571,-.010064,
-.009,-.010464,
-.008368,-.010759,
-.007695,-.010939,
-.007,-.011,
.007,-.011,
.007695,-.010939,
.008368,-.010759,
.009,-.010464,
.009571,-.010064,
.010064,-.009571,
.010464,-.009,
.010759,-.008368,
.010939,-.007695,
.011,-.007,
0.0*
%
%ADD32MACRO32*%
%AMMACRO18*
4,1,40,.007,.011,
-.007,.011,
-.007695,.010939,
-.008368,.010759,
-.009,.010464,
-.009571,.010064,
-.010064,.009571,
-.010464,.009,
-.010759,.008368,
-.010939,.007695,
-.011,.007,
-.011,-.007,
-.010939,-.007695,
-.010759,-.008368,
-.010464,-.009,
-.010064,-.009571,
-.009571,-.010064,
-.009,-.010464,
-.008368,-.010759,
-.007695,-.010939,
-.007,-.011,
.007,-.011,
.007695,-.010939,
.008368,-.010759,
.009,-.010464,
.009571,-.010064,
.010064,-.009571,
.010464,-.009,
.010759,-.008368,
.010939,-.007695,
.011,-.007,
.011,.007,
.010939,.007695,
.010759,.008368,
.010464,.009,
.010064,.009571,
.009571,.010064,
.009,.010464,
.008368,.010759,
.007695,.010939,
.007,.011,
0.0*
%
%ADD18MACRO18*%
%AMMACRO55*
4,1,40,-.012,.008,
-.012,-.008,
-.011939,-.008695,
-.011759,-.009368,
-.011464,-.01,
-.011064,-.010571,
-.010571,-.011064,
-.01,-.011464,
-.009368,-.011759,
-.008695,-.011939,
-.008,-.012,
.008,-.012,
.008695,-.011939,
.009368,-.011759,
.01,-.011464,
.010571,-.011064,
.011064,-.010571,
.011464,-.01,
.011759,-.009368,
.011939,-.008695,
.012,-.008,
.012,.008,
.011939,.008695,
.011759,.009368,
.011464,.01,
.011064,.010571,
.010571,.011064,
.01,.011464,
.009368,.011759,
.008695,.011939,
.008,.012,
-.008,.012,
-.008695,.011939,
-.009368,.011759,
-.01,.011464,
-.010571,.011064,
-.011064,.010571,
-.011464,.01,
-.011759,.009368,
-.011939,.008695,
-.012,.008,
0.0*
%
%ADD55MACRO55*%
%AMMACRO35*
4,1,40,.008,.012,
-.008,.012,
-.008695,.011939,
-.009368,.011759,
-.01,.011464,
-.010571,.011064,
-.011064,.010571,
-.011464,.01,
-.011759,.009368,
-.011939,.008695,
-.012,.008,
-.012,-.008,
-.011939,-.008695,
-.011759,-.009368,
-.011464,-.01,
-.011064,-.010571,
-.010571,-.011064,
-.01,-.011464,
-.009368,-.011759,
-.008695,-.011939,
-.008,-.012,
.008,-.012,
.008695,-.011939,
.009368,-.011759,
.01,-.011464,
.010571,-.011064,
.011064,-.010571,
.011464,-.01,
.011759,-.009368,
.011939,-.008695,
.012,-.008,
.012,.008,
.011939,.008695,
.011759,.009368,
.011464,.01,
.011064,.010571,
.010571,.011064,
.01,.011464,
.009368,.011759,
.008695,.011939,
.008,.012,
0.0*
%
%ADD35MACRO35*%
%AMMACRO31*
4,1,40,-.013,-.017,
.013,-.017,
.013695,-.016939,
.014368,-.016759,
.015,-.016464,
.015571,-.016064,
.016064,-.015571,
.016464,-.015,
.016759,-.014368,
.016939,-.013695,
.017,-.013,
.017,.013,
.016939,.013695,
.016759,.014368,
.016464,.015,
.016064,.015571,
.015571,.016064,
.015,.016464,
.014368,.016759,
.013695,.016939,
.013,.017,
-.013,.017,
-.013695,.016939,
-.014368,.016759,
-.015,.016464,
-.015571,.016064,
-.016064,.015571,
-.016464,.015,
-.016759,.014368,
-.016939,.013695,
-.017,.013,
-.017,-.013,
-.016939,-.013695,
-.016759,-.014368,
-.016464,-.015,
-.016064,-.015571,
-.015571,-.016064,
-.015,-.016464,
-.014368,-.016759,
-.013695,-.016939,
-.013,-.017,
0.0*
%
%ADD31MACRO31*%
%AMMACRO36*
4,1,40,-.017,.013,
-.017,-.013,
-.016939,-.013695,
-.016759,-.014368,
-.016464,-.015,
-.016064,-.015571,
-.015571,-.016064,
-.015,-.016464,
-.014368,-.016759,
-.013695,-.016939,
-.013,-.017,
.013,-.017,
.013695,-.016939,
.014368,-.016759,
.015,-.016464,
.015571,-.016064,
.016064,-.015571,
.016464,-.015,
.016759,-.014368,
.016939,-.013695,
.017,-.013,
.017,.013,
.016939,.013695,
.016759,.014368,
.016464,.015,
.016064,.015571,
.015571,.016064,
.015,.016464,
.014368,.016759,
.013695,.016939,
.013,.017,
-.013,.017,
-.013695,.016939,
-.014368,.016759,
-.015,.016464,
-.015571,.016064,
-.016064,.015571,
-.016464,.015,
-.016759,.014368,
-.016939,.013695,
-.017,.013,
0.0*
%
%ADD36MACRO36*%
%AMMACRO33*
4,1,40,.011,-.007,
.011,.007,
.010939,.007695,
.010759,.008368,
.010464,.009,
.010064,.009571,
.009571,.010064,
.009,.010464,
.008368,.010759,
.007695,.010939,
.007,.011,
-.007,.011,
-.007695,.010939,
-.008368,.010759,
-.009,.010464,
-.009571,.010064,
-.010064,.009571,
-.010464,.009,
-.010759,.008368,
-.010939,.007695,
-.011,.007,
-.011,-.007,
-.010939,-.007695,
-.010759,-.008368,
-.010464,-.009,
-.010064,-.009571,
-.009571,-.010064,
-.009,-.010464,
-.008368,-.010759,
-.007695,-.010939,
-.007,-.011,
.007,-.011,
.007695,-.010939,
.008368,-.010759,
.009,-.010464,
.009571,-.010064,
.010064,-.009571,
.010464,-.009,
.010759,-.008368,
.010939,-.007695,
.011,-.007,
0.0*
%
%ADD33MACRO33*%
%AMMACRO21*
4,1,40,.007,.011,
-.007,.011,
-.007695,.010939,
-.008368,.010759,
-.009,.010464,
-.009571,.010064,
-.010064,.009571,
-.010464,.009,
-.010759,.008368,
-.010939,.007695,
-.011,.007,
-.011,-.007,
-.010939,-.007695,
-.010759,-.008368,
-.010464,-.009,
-.010064,-.009571,
-.009571,-.010064,
-.009,-.010464,
-.008368,-.010759,
-.007695,-.010939,
-.007,-.011,
.007,-.011,
.007695,-.010939,
.008368,-.010759,
.009,-.010464,
.009571,-.010064,
.010064,-.009571,
.010464,-.009,
.010759,-.008368,
.010939,-.007695,
.011,-.007,
.011,.007,
.010939,.007695,
.010759,.008368,
.010464,.009,
.010064,.009571,
.009571,.010064,
.009,.010464,
.008368,.010759,
.007695,.010939,
.007,.011,
0.0*
%
%ADD21MACRO21*%
%AMMACRO54*
4,1,40,-.012,.008,
-.012,-.008,
-.011939,-.008695,
-.011759,-.009368,
-.011464,-.01,
-.011064,-.010571,
-.010571,-.011064,
-.01,-.011464,
-.009368,-.011759,
-.008695,-.011939,
-.008,-.012,
.008,-.012,
.008695,-.011939,
.009368,-.011759,
.01,-.011464,
.010571,-.011064,
.011064,-.010571,
.011464,-.01,
.011759,-.009368,
.011939,-.008695,
.012,-.008,
.012,.008,
.011939,.008695,
.011759,.009368,
.011464,.01,
.011064,.010571,
.010571,.011064,
.01,.011464,
.009368,.011759,
.008695,.011939,
.008,.012,
-.008,.012,
-.008695,.011939,
-.009368,.011759,
-.01,.011464,
-.010571,.011064,
-.011064,.010571,
-.011464,.01,
-.011759,.009368,
-.011939,.008695,
-.012,.008,
0.0*
%
%ADD54MACRO54*%
%AMMACRO34*
4,1,40,.008,.012,
-.008,.012,
-.008695,.011939,
-.009368,.011759,
-.01,.011464,
-.010571,.011064,
-.011064,.010571,
-.011464,.01,
-.011759,.009368,
-.011939,.008695,
-.012,.008,
-.012,-.008,
-.011939,-.008695,
-.011759,-.009368,
-.011464,-.01,
-.011064,-.010571,
-.010571,-.011064,
-.01,-.011464,
-.009368,-.011759,
-.008695,-.011939,
-.008,-.012,
.008,-.012,
.008695,-.011939,
.009368,-.011759,
.01,-.011464,
.010571,-.011064,
.011064,-.010571,
.011464,-.01,
.011759,-.009368,
.011939,-.008695,
.012,-.008,
.012,.008,
.011939,.008695,
.011759,.009368,
.011464,.01,
.011064,.010571,
.010571,.011064,
.01,.011464,
.009368,.011759,
.008695,.011939,
.008,.012,
0.0*
%
%ADD34MACRO34*%
%AMMACRO25*
4,1,40,-.013,-.017,
.013,-.017,
.013695,-.016939,
.014368,-.016759,
.015,-.016464,
.015571,-.016064,
.016064,-.015571,
.016464,-.015,
.016759,-.014368,
.016939,-.013695,
.017,-.013,
.017,.013,
.016939,.013695,
.016759,.014368,
.016464,.015,
.016064,.015571,
.015571,.016064,
.015,.016464,
.014368,.016759,
.013695,.016939,
.013,.017,
-.013,.017,
-.013695,.016939,
-.014368,.016759,
-.015,.016464,
-.015571,.016064,
-.016064,.015571,
-.016464,.015,
-.016759,.014368,
-.016939,.013695,
-.017,.013,
-.017,-.013,
-.016939,-.013695,
-.016759,-.014368,
-.016464,-.015,
-.016064,-.015571,
-.015571,-.016064,
-.015,-.016464,
-.014368,-.016759,
-.013695,-.016939,
-.013,-.017,
0.0*
%
%ADD25MACRO25*%
%AMMACRO37*
4,1,40,-.017,.013,
-.017,-.013,
-.016939,-.013695,
-.016759,-.014368,
-.016464,-.015,
-.016064,-.015571,
-.015571,-.016064,
-.015,-.016464,
-.014368,-.016759,
-.013695,-.016939,
-.013,-.017,
.013,-.017,
.013695,-.016939,
.014368,-.016759,
.015,-.016464,
.015571,-.016064,
.016064,-.015571,
.016464,-.015,
.016759,-.014368,
.016939,-.013695,
.017,-.013,
.017,.013,
.016939,.013695,
.016759,.014368,
.016464,.015,
.016064,.015571,
.015571,.016064,
.015,.016464,
.014368,.016759,
.013695,.016939,
.013,.017,
-.013,.017,
-.013695,.016939,
-.014368,.016759,
-.015,.016464,
-.015571,.016064,
-.016064,.015571,
-.016464,.015,
-.016759,.014368,
-.016939,.013695,
-.017,.013,
0.0*
%
%ADD37MACRO37*%
%ADD41R,.135X.101*%
%ADD72R,.022X.04*%
%ADD49R,.04X.023*%
%ADD58R,.06X.012*%
%ADD57R,.012X.06*%
%ADD63R,.04X.016*%
%ADD62R,.014X.06*%
%ADD22R,.045X.03*%
%ADD12R,.03X.045*%
%ADD70R,.03X.046*%
%ADD40R,.03X.064*%
%ADD10C,.14*%
%ADD66R,.045X.016*%
%ADD65R,.016X.045*%
%ADD61R,.08X.071*%
%ADD13R,.05X.065*%
%ADD47R,.065X.05*%
%ADD68R,.071X.063*%
%ADD60R,.065X.025*%
%ADD26R,.055X.035*%
%ADD53R,.09X.045*%
%ADD51R,.045X.055*%
%ADD50R,.035X.055*%
%ADD46R,.048X.016*%
%ADD59R,.055X.045*%
%ADD45R,.016X.048*%
%ADD67R,.122X.122*%
%ADD17R,.09X.095*%
%AMMACRO71*
4,1,40,.007,.0225,
.008389,.022378,
.009736,.022018,
.011,.021428,
.012142,.020628,
.013128,.019642,
.013928,.0185,
.014518,.017236,
.014878,.015889,
.015,.0145,
.015,-.0145,
.014878,-.015889,
.014518,-.017236,
.013928,-.0185,
.013128,-.019642,
.012142,-.020628,
.011,-.021428,
.009736,-.022018,
.008389,-.022378,
.007,-.0225,
-.007,-.0225,
-.008389,-.022378,
-.009736,-.022018,
-.011,-.021428,
-.012142,-.020628,
-.013128,-.019642,
-.013928,-.0185,
-.014518,-.017236,
-.014878,-.015889,
-.015,-.0145,
-.015,.0145,
-.014878,.015889,
-.014518,.017236,
-.013928,.0185,
-.013128,.019642,
-.012142,.020628,
-.011,.021428,
-.009736,.022018,
-.008389,.022378,
-.007,.0225,
.007,.0225,
0.0*
%
%ADD71MACRO71*%
%ADD52R,.095X.09*%
%ADD48R,.059X.089*%
%AMMACRO43*
4,1,40,-.008,-.012,
.008,-.012,
.008695,-.011939,
.009368,-.011759,
.01,-.011464,
.010571,-.011064,
.011064,-.010571,
.011464,-.01,
.011759,-.009368,
.011939,-.008695,
.012,-.008,
.012,.008,
.011939,.008695,
.011759,.009368,
.011464,.01,
.011064,.010571,
.010571,.011064,
.01,.011464,
.009368,.011759,
.008695,.011939,
.008,.012,
-.008,.012,
-.008695,.011939,
-.009368,.011759,
-.01,.011464,
-.010571,.011064,
-.011064,.010571,
-.011464,.01,
-.011759,.009368,
-.011939,.008695,
-.012,.008,
-.012,-.008,
-.011939,-.008695,
-.011759,-.009368,
-.011464,-.01,
-.011064,-.010571,
-.010571,-.011064,
-.01,-.011464,
-.009368,-.011759,
-.008695,-.011939,
-.008,-.012,
0.0*
%
%ADD43MACRO43*%
%AMMACRO28*
4,1,40,.012,-.008,
.012,.008,
.011939,.008695,
.011759,.009368,
.011464,.01,
.011064,.010571,
.010571,.011064,
.01,.011464,
.009368,.011759,
.008695,.011939,
.008,.012,
-.008,.012,
-.008695,.011939,
-.009368,.011759,
-.01,.011464,
-.010571,.011064,
-.011064,.010571,
-.011464,.01,
-.011759,.009368,
-.011939,.008695,
-.012,.008,
-.012,-.008,
-.011939,-.008695,
-.011759,-.009368,
-.011464,-.01,
-.011064,-.010571,
-.010571,-.011064,
-.01,-.011464,
-.009368,-.011759,
-.008695,-.011939,
-.008,-.012,
.008,-.012,
.008695,-.011939,
.009368,-.011759,
.01,-.011464,
.010571,-.011064,
.011064,-.010571,
.011464,-.01,
.011759,-.009368,
.011939,-.008695,
.012,-.008,
0.0*
%
%ADD28MACRO28*%
%AMMACRO23*
4,1,40,-.007,-.011,
.007,-.011,
.007695,-.010939,
.008368,-.010759,
.009,-.010464,
.009571,-.010064,
.010064,-.009571,
.010464,-.009,
.010759,-.008368,
.010939,-.007695,
.011,-.007,
.011,.007,
.010939,.007695,
.010759,.008368,
.010464,.009,
.010064,.009571,
.009571,.010064,
.009,.010464,
.008368,.010759,
.007695,.010939,
.007,.011,
-.007,.011,
-.007695,.010939,
-.008368,.010759,
-.009,.010464,
-.009571,.010064,
-.010064,.009571,
-.010464,.009,
-.010759,.008368,
-.010939,.007695,
-.011,.007,
-.011,-.007,
-.010939,-.007695,
-.010759,-.008368,
-.010464,-.009,
-.010064,-.009571,
-.009571,-.010064,
-.009,-.010464,
-.008368,-.010759,
-.007695,-.010939,
-.007,-.011,
0.0*
%
%ADD23MACRO23*%
%AMMACRO14*
4,1,40,-.011,.007,
-.011,-.007,
-.010939,-.007695,
-.010759,-.008368,
-.010464,-.009,
-.010064,-.009571,
-.009571,-.010064,
-.009,-.010464,
-.008368,-.010759,
-.007695,-.010939,
-.007,-.011,
.007,-.011,
.007695,-.010939,
.008368,-.010759,
.009,-.010464,
.009571,-.010064,
.010064,-.009571,
.010464,-.009,
.010759,-.008368,
.010939,-.007695,
.011,-.007,
.011,.007,
.010939,.007695,
.010759,.008368,
.010464,.009,
.010064,.009571,
.009571,.010064,
.009,.010464,
.008368,.010759,
.007695,.010939,
.007,.011,
-.007,.011,
-.007695,.010939,
-.008368,.010759,
-.009,.010464,
-.009571,.010064,
-.010064,.009571,
-.010464,.009,
-.010759,.008368,
-.010939,.007695,
-.011,.007,
0.0*
%
%ADD14MACRO14*%
%AMMACRO30*
4,1,40,.013,.017,
-.013,.017,
-.013695,.016939,
-.014368,.016759,
-.015,.016464,
-.015571,.016064,
-.016064,.015571,
-.016464,.015,
-.016759,.014368,
-.016939,.013695,
-.017,.013,
-.017,-.013,
-.016939,-.013695,
-.016759,-.014368,
-.016464,-.015,
-.016064,-.015571,
-.015571,-.016064,
-.015,-.016464,
-.014368,-.016759,
-.013695,-.016939,
-.013,-.017,
.013,-.017,
.013695,-.016939,
.014368,-.016759,
.015,-.016464,
.015571,-.016064,
.016064,-.015571,
.016464,-.015,
.016759,-.014368,
.016939,-.013695,
.017,-.013,
.017,.013,
.016939,.013695,
.016759,.014368,
.016464,.015,
.016064,.015571,
.015571,.016064,
.015,.016464,
.014368,.016759,
.013695,.016939,
.013,.017,
0.0*
%
%ADD30MACRO30*%
%AMMACRO19*
4,1,40,.017,-.013,
.017,.013,
.016939,.013695,
.016759,.014368,
.016464,.015,
.016064,.015571,
.015571,.016064,
.015,.016464,
.014368,.016759,
.013695,.016939,
.013,.017,
-.013,.017,
-.013695,.016939,
-.014368,.016759,
-.015,.016464,
-.015571,.016064,
-.016064,.015571,
-.016464,.015,
-.016759,.014368,
-.016939,.013695,
-.017,.013,
-.017,-.013,
-.016939,-.013695,
-.016759,-.014368,
-.016464,-.015,
-.016064,-.015571,
-.015571,-.016064,
-.015,-.016464,
-.014368,-.016759,
-.013695,-.016939,
-.013,-.017,
.013,-.017,
.013695,-.016939,
.014368,-.016759,
.015,-.016464,
.015571,-.016064,
.016064,-.015571,
.016464,-.015,
.016759,-.014368,
.016939,-.013695,
.017,-.013,
0.0*
%
%ADD19MACRO19*%
%AMMACRO42*
4,1,40,-.008,-.012,
.008,-.012,
.008695,-.011939,
.009368,-.011759,
.01,-.011464,
.010571,-.011064,
.011064,-.010571,
.011464,-.01,
.011759,-.009368,
.011939,-.008695,
.012,-.008,
.012,.008,
.011939,.008695,
.011759,.009368,
.011464,.01,
.011064,.010571,
.010571,.011064,
.01,.011464,
.009368,.011759,
.008695,.011939,
.008,.012,
-.008,.012,
-.008695,.011939,
-.009368,.011759,
-.01,.011464,
-.010571,.011064,
-.011064,.010571,
-.011464,.01,
-.011759,.009368,
-.011939,.008695,
-.012,.008,
-.012,-.008,
-.011939,-.008695,
-.011759,-.009368,
-.011464,-.01,
-.011064,-.010571,
-.010571,-.011064,
-.01,-.011464,
-.009368,-.011759,
-.008695,-.011939,
-.008,-.012,
0.0*
%
%ADD42MACRO42*%
%AMMACRO27*
4,1,40,.012,-.008,
.012,.008,
.011939,.008695,
.011759,.009368,
.011464,.01,
.011064,.010571,
.010571,.011064,
.01,.011464,
.009368,.011759,
.008695,.011939,
.008,.012,
-.008,.012,
-.008695,.011939,
-.009368,.011759,
-.01,.011464,
-.010571,.011064,
-.011064,.010571,
-.011464,.01,
-.011759,.009368,
-.011939,.008695,
-.012,.008,
-.012,-.008,
-.011939,-.008695,
-.011759,-.009368,
-.011464,-.01,
-.011064,-.010571,
-.010571,-.011064,
-.01,-.011464,
-.009368,-.011759,
-.008695,-.011939,
-.008,-.012,
.008,-.012,
.008695,-.011939,
.009368,-.011759,
.01,-.011464,
.010571,-.011064,
.011064,-.010571,
.011464,-.01,
.011759,-.009368,
.011939,-.008695,
.012,-.008,
0.0*
%
%ADD27MACRO27*%
%AMMACRO16*
4,1,40,-.007,-.011,
.007,-.011,
.007695,-.010939,
.008368,-.010759,
.009,-.010464,
.009571,-.010064,
.010064,-.009571,
.010464,-.009,
.010759,-.008368,
.010939,-.007695,
.011,-.007,
.011,.007,
.010939,.007695,
.010759,.008368,
.010464,.009,
.010064,.009571,
.009571,.010064,
.009,.010464,
.008368,.010759,
.007695,.010939,
.007,.011,
-.007,.011,
-.007695,.010939,
-.008368,.010759,
-.009,.010464,
-.009571,.010064,
-.010064,.009571,
-.010464,.009,
-.010759,.008368,
-.010939,.007695,
-.011,.007,
-.011,-.007,
-.010939,-.007695,
-.010759,-.008368,
-.010464,-.009,
-.010064,-.009571,
-.009571,-.010064,
-.009,-.010464,
-.008368,-.010759,
-.007695,-.010939,
-.007,-.011,
0.0*
%
%ADD16MACRO16*%
%AMMACRO15*
4,1,40,-.011,.007,
-.011,-.007,
-.010939,-.007695,
-.010759,-.008368,
-.010464,-.009,
-.010064,-.009571,
-.009571,-.010064,
-.009,-.010464,
-.008368,-.010759,
-.007695,-.010939,
-.007,-.011,
.007,-.011,
.007695,-.010939,
.008368,-.010759,
.009,-.010464,
.009571,-.010064,
.010064,-.009571,
.010464,-.009,
.010759,-.008368,
.010939,-.007695,
.011,-.007,
.011,.007,
.010939,.007695,
.010759,.008368,
.010464,.009,
.010064,.009571,
.009571,.010064,
.009,.010464,
.008368,.010759,
.007695,.010939,
.007,.011,
-.007,.011,
-.007695,.010939,
-.008368,.010759,
-.009,.010464,
-.009571,.010064,
-.010064,.009571,
-.010464,.009,
-.010759,.008368,
-.010939,.007695,
-.011,.007,
0.0*
%
%ADD15MACRO15*%
%ADD73C,.02*%
%ADD74C,.006*%
G75*
%LPD*%
G75*
G36*
G01X77800Y444315D02*
X86350D01*
Y453265D01*
X77800D01*
Y444315D01*
G37*
G36*
G01X66650D02*
X75200D01*
Y453265D01*
X66650D01*
Y444315D01*
G37*
G36*
G01X77800Y455865D02*
X86350D01*
Y464815D01*
X77800D01*
Y455865D01*
G37*
G36*
G01X66650D02*
X75200D01*
Y464815D01*
X66650D01*
Y455865D01*
G37*
G36*
G01X69200Y1579915D02*
X77750D01*
Y1588865D01*
X69200D01*
Y1579915D01*
G37*
G36*
G01X58050D02*
X66600D01*
Y1588865D01*
X58050D01*
Y1579915D01*
G37*
G36*
G01X69200Y1591465D02*
X77750D01*
Y1600415D01*
X69200D01*
Y1591465D01*
G37*
G36*
G01X58050D02*
X66600D01*
Y1600415D01*
X58050D01*
Y1591465D01*
G37*
G36*
G01X105300Y443815D02*
X113850D01*
Y452765D01*
X105300D01*
Y443815D01*
G37*
G36*
G01X94150D02*
X102700D01*
Y452765D01*
X94150D01*
Y443815D01*
G37*
G36*
G01X105300Y455365D02*
X113850D01*
Y464315D01*
X105300D01*
Y455365D01*
G37*
G36*
G01X94150D02*
X102700D01*
Y464315D01*
X94150D01*
Y455365D01*
G37*
G36*
G01X108556Y686015D02*
Y692015D01*
X104356D01*
Y686015D01*
X108556D01*
G37*
G36*
G01Y677815D02*
Y683815D01*
X104356D01*
Y677815D01*
X108556D01*
G37*
G36*
G01X102156Y686015D02*
Y692015D01*
X97956D01*
Y686015D01*
X102156D01*
G37*
G36*
G01Y677815D02*
Y683815D01*
X97956D01*
Y677815D01*
X102156D01*
G37*
G36*
G01X126150Y1579815D02*
X134700D01*
Y1588765D01*
X126150D01*
Y1579815D01*
G37*
G36*
G01Y1591365D02*
X134700D01*
Y1600315D01*
X126150D01*
Y1591365D01*
G37*
G36*
G01X102300Y1579815D02*
X110850D01*
Y1588765D01*
X102300D01*
Y1579815D01*
G37*
G36*
G01X91150D02*
X99700D01*
Y1588765D01*
X91150D01*
Y1579815D01*
G37*
G36*
G01X102300Y1591365D02*
X110850D01*
Y1600315D01*
X102300D01*
Y1591365D01*
G37*
G36*
G01X91150D02*
X99700D01*
Y1600315D01*
X91150D01*
Y1591365D01*
G37*
G36*
G01X149800Y443815D02*
X158350D01*
Y452765D01*
X149800D01*
Y443815D01*
G37*
G36*
G01X138650D02*
X147200D01*
Y452765D01*
X138650D01*
Y443815D01*
G37*
G36*
G01X177800D02*
X186350D01*
Y452765D01*
X177800D01*
Y443815D01*
G37*
G36*
G01X166650D02*
X175200D01*
Y452765D01*
X166650D01*
Y443815D01*
G37*
G36*
G01X149800Y455365D02*
X158350D01*
Y464315D01*
X149800D01*
Y455365D01*
G37*
G36*
G01X138650D02*
X147200D01*
Y464315D01*
X138650D01*
Y455365D01*
G37*
G36*
G01X177800D02*
X186350D01*
Y464315D01*
X177800D01*
Y455365D01*
G37*
G36*
G01X166650D02*
X175200D01*
Y464315D01*
X166650D01*
Y455365D01*
G37*
G36*
G01X171300Y1579815D02*
X179850D01*
Y1588765D01*
X171300D01*
Y1579815D01*
G37*
G36*
G01X160150D02*
X168700D01*
Y1588765D01*
X160150D01*
Y1579815D01*
G37*
G36*
G01X171300Y1591365D02*
X179850D01*
Y1600315D01*
X171300D01*
Y1591365D01*
G37*
G36*
G01X160150D02*
X168700D01*
Y1600315D01*
X160150D01*
Y1591365D01*
G37*
G36*
G01X137300Y1579815D02*
X145850D01*
Y1588765D01*
X137300D01*
Y1579815D01*
G37*
G36*
G01Y1591365D02*
X145850D01*
Y1600315D01*
X137300D01*
Y1591365D01*
G37*
G54D10*
X-222440Y19685D03*
Y1948818D03*
X643700Y19685D03*
Y1948818D03*
G54D11*
X-181139Y20007D03*
X-180444Y1947256D03*
X150000Y64500D03*
X152500Y1906000D03*
X601704Y21248D03*
X602399Y1948497D03*
G54D20*
X24100Y685300D03*
X28900D03*
X74100Y570600D03*
X82000Y702600D03*
X65635Y688306D03*
X70535D03*
X72200Y705400D03*
X67200D03*
X70800Y975800D03*
X64200Y998500D03*
X81398Y1132153D03*
X92300Y872854D03*
X87500D03*
X94000Y957200D03*
X103500Y974200D03*
X129900Y986900D03*
X140400Y566800D03*
X158535Y604079D03*
G54D30*
X78247Y61398D03*
X50600Y252800D03*
X34400Y294300D03*
X67900Y591000D03*
X71000Y986600D03*
X62000Y1025000D03*
X111300Y380100D03*
X85929Y533679D03*
X101500Y986000D03*
Y990800D03*
X89200Y1455500D03*
X101200Y1474500D03*
X160300Y532100D03*
X160100Y553300D03*
X176421Y613535D03*
X154700Y1462500D03*
G54D12*
X27471Y262553D03*
X19721D03*
X23596Y255053D03*
X24925Y305350D03*
X28800Y312850D03*
X27625Y1649050D03*
X27292Y1714868D03*
X19542D03*
X23417Y1707368D03*
X32675Y305350D03*
X54817Y902368D03*
X58692Y909868D03*
X50942D03*
X78752Y1613297D03*
Y1619703D03*
X35375Y1649050D03*
X31500Y1641550D03*
X131525Y722550D03*
X109252Y1613297D03*
Y1619703D03*
X141625Y682250D03*
X149375D03*
X145500Y689750D03*
X139275Y722550D03*
X135400Y730050D03*
X148025Y1401454D03*
X155775D03*
X151900Y1408954D03*
X165494Y1437469D03*
X173244D03*
X169369Y1444969D03*
X138694Y1422269D03*
X146444D03*
X142569Y1429769D03*
X137752Y1613297D03*
Y1619703D03*
X165252Y1613297D03*
Y1619703D03*
G54D21*
X27700Y1106000D03*
X22000Y1640200D03*
X23300Y1769600D03*
X70700Y63500D03*
X60300Y171300D03*
Y183300D03*
Y167300D03*
Y187300D03*
X61200Y221000D03*
X49900Y217400D03*
X36082Y264217D03*
X60300Y280000D03*
X33400Y570800D03*
X68700Y730000D03*
X72100Y1004300D03*
X63000Y1020600D03*
X75700Y1025400D03*
X75800Y1020900D03*
X41400Y1096000D03*
X72200Y1175100D03*
X34100Y1774400D03*
X38400Y1788200D03*
X102100Y549600D03*
X87100Y569900D03*
X81944Y694635D03*
X94700Y671000D03*
X119000Y660200D03*
X108300Y662200D03*
X83400Y682200D03*
X91200Y707900D03*
X89700Y733400D03*
X107500Y1408100D03*
X94700Y1446500D03*
X113100Y1421600D03*
X153500Y430800D03*
X148700Y568000D03*
X156200Y587000D03*
X166100Y626700D03*
X177700Y624300D03*
X151404Y1394000D03*
X133200Y1428300D03*
X143900Y1466400D03*
Y1462400D03*
X143600Y1453300D03*
X160700Y1458000D03*
G54D13*
X27900Y246900D03*
X25300Y328500D03*
X16200Y1657100D03*
X27200D03*
X15800Y1699200D03*
X26800D03*
X38900Y246900D03*
X36300Y328500D03*
X124696Y1392300D03*
X106000Y1387500D03*
X117000D03*
X135696Y1392300D03*
X154000Y1387500D03*
X143000D03*
G54D40*
X69000Y440000D03*
X74000D03*
X79000D03*
X60400Y1575600D03*
X65400D03*
X70400D03*
X75400D03*
X96500Y439500D03*
X101500D03*
X106500D03*
X111500D03*
X84000Y440000D03*
X128500Y1575500D03*
X93500D03*
X98500D03*
X103500D03*
X108500D03*
X141000Y439500D03*
X146000D03*
X151000D03*
X156000D03*
X169000D03*
X174000D03*
X179000D03*
X184000D03*
X162500Y1575500D03*
X167500D03*
X172500D03*
X177500D03*
X133500D03*
X138500D03*
X143500D03*
G54D22*
X24368Y1093083D03*
X31868Y1089208D03*
Y1096958D03*
X112018Y566991D03*
Y574741D03*
X104518Y570866D03*
X112018Y1255968D03*
Y1263718D03*
X104518Y1259843D03*
G54D31*
X81300Y71500D03*
X63800Y662300D03*
Y657600D03*
X54300Y1764700D03*
X33600Y1769900D03*
X115800Y769100D03*
Y764100D03*
X105300Y1058400D03*
Y1053700D03*
X147447Y1878698D03*
X147400Y1883700D03*
X187900Y1652700D03*
Y1648000D03*
G54D14*
X19283Y307282D03*
X25900Y1721700D03*
X57400Y207900D03*
X56900Y236600D03*
X56600Y191600D03*
X32700Y253500D03*
X63000Y264300D03*
X39200Y343800D03*
X81400Y530500D03*
X78400Y587600D03*
X49600Y573500D03*
X61400Y673400D03*
X57400D03*
X64100Y909400D03*
X77002Y1134497D03*
X32900Y1660800D03*
X96100Y530500D03*
X124900Y585204D03*
X120800D03*
X93065Y594071D03*
X97265D03*
X92465Y606971D03*
X95200Y662300D03*
X110900Y881400D03*
X102600D03*
X119300D03*
X122529Y952344D03*
X117529D03*
X112529D03*
X100500Y1420300D03*
X91500D03*
X83500Y1461800D03*
X105000Y1420300D03*
X107500Y1486800D03*
X170600Y529100D03*
X155600Y529000D03*
X158000Y575200D03*
X170200Y623700D03*
X180365Y642371D03*
X137765Y658671D03*
X154500Y683800D03*
X149500Y708300D03*
X147900Y999700D03*
X152100Y999800D03*
X163500Y994300D03*
X159500D03*
X143800Y999800D03*
X135000Y1408404D03*
X134700Y1400604D03*
X137500Y1440300D03*
G54D23*
X22000Y1644300D03*
X21800Y1720700D03*
X23600Y1692800D03*
X60300Y155300D03*
Y163300D03*
Y179300D03*
Y159300D03*
Y175300D03*
X49900Y213400D03*
X61200Y217000D03*
X60300Y199300D03*
X36200Y272300D03*
X32500Y321300D03*
X74200Y431300D03*
X64400Y577200D03*
X48800Y916400D03*
X72100Y999800D03*
X33500Y1083600D03*
X52800Y1769800D03*
X91703Y61502D03*
X89200Y71500D03*
X121300Y437500D03*
X81956Y690465D03*
X84100Y686400D03*
X129356Y692165D03*
X129256Y688065D03*
Y683665D03*
X116300Y670600D03*
X87396Y848500D03*
Y844100D03*
Y852900D03*
X87400Y865700D03*
Y857200D03*
Y861500D03*
X115300Y1408200D03*
X94700Y1451000D03*
X113100Y1425900D03*
X94700Y1439000D03*
X87700Y1484000D03*
X132200Y1482000D03*
X163300Y545600D03*
X166100Y622700D03*
X155729Y615065D03*
X175200Y701100D03*
X155496Y1415000D03*
X143900Y1458400D03*
X155500Y1423400D03*
X155496Y1419200D03*
X194200Y439500D03*
G54D50*
X70202Y1138347D03*
Y1125047D03*
X41600Y1767550D03*
Y1754250D03*
X88502Y1136247D03*
Y1122947D03*
G54D41*
X72000Y473548D03*
Y491452D03*
X90000Y473548D03*
Y491452D03*
X176000Y473048D03*
Y490952D03*
X158000Y473048D03*
Y490952D03*
G54D32*
X67998Y56503D03*
X67398Y71003D03*
X61000Y240000D03*
X61600Y211300D03*
X60600Y195000D03*
X54300Y263300D03*
X58300D03*
X37200Y256900D03*
X62600Y249200D03*
X73700Y543300D03*
X78600Y574500D03*
X73900Y558800D03*
X39000Y581300D03*
X77200Y705900D03*
X77000Y730800D03*
X43400Y896100D03*
X81398Y1126103D03*
X63498Y1123803D03*
X63198Y1142003D03*
X48300Y1755700D03*
X116800Y588596D03*
X128900D03*
X91300Y573200D03*
X129335Y662029D03*
X104900Y662200D03*
X115600Y660200D03*
X116300Y670600D03*
X119600Y831800D03*
X111200D03*
X102900Y831796D03*
X121671Y939756D03*
X117300Y939700D03*
X110500D03*
X131500Y947800D03*
X123300Y1001300D03*
X119300D03*
X114800D03*
X99000Y979700D03*
X123000Y1424200D03*
X127500D03*
X95500Y1464200D03*
X118000Y1424200D03*
X95600Y1423700D03*
X129000Y1501700D03*
X125000D03*
X121000D03*
X117000D03*
X113000D03*
X109000D03*
X93500Y1479200D03*
X136779Y543071D03*
X145300Y582200D03*
X153500Y570000D03*
X136679Y557171D03*
X151335Y635829D03*
X148435Y653329D03*
X133535Y662029D03*
X144235Y653329D03*
X167700Y699600D03*
X154500Y702700D03*
X158500D03*
X149000Y949200D03*
X153000D03*
X157000D03*
X145000D03*
X140500Y947800D03*
X136000D03*
X139100Y1003100D03*
X135000Y1003200D03*
X156631Y1431081D03*
X160831Y1430281D03*
X152331Y1431081D03*
X165400Y1430200D03*
X151000Y1491200D03*
X146500D03*
X142000D03*
X137000Y1501700D03*
X133000D03*
X137900Y1491100D03*
X148500Y1474100D03*
G54D15*
X19283Y310682D03*
X25900Y1725100D03*
X57400Y211300D03*
X56900Y240000D03*
X56600Y195000D03*
X32700Y256900D03*
X63000Y267700D03*
X39200Y347200D03*
X81400Y533900D03*
X78400Y591000D03*
X49600Y576900D03*
X61400Y676800D03*
X57400D03*
X64100Y912800D03*
X77002Y1137897D03*
X32900Y1664200D03*
X96100Y533900D03*
X124900Y588604D03*
X120800D03*
X93065Y597471D03*
X97265D03*
X92465Y610371D03*
X95200Y665700D03*
X110900Y884800D03*
X102600D03*
X119300D03*
X122529Y955744D03*
X117529D03*
X112529D03*
X100500Y1423700D03*
X91500D03*
X83500Y1465200D03*
X105000Y1423700D03*
X107500Y1490200D03*
X170600Y532500D03*
X155600Y532400D03*
X158000Y578600D03*
X170200Y627100D03*
X180365Y645771D03*
X137765Y662071D03*
X154500Y687200D03*
X149500Y711700D03*
X147900Y1003100D03*
X152100Y1003200D03*
X163500Y997700D03*
X159500D03*
X143800Y1003200D03*
X135000Y1411804D03*
X134700Y1404004D03*
X137500Y1443700D03*
G54D42*
X35000Y581300D03*
X58100Y1030800D03*
X87400Y574100D03*
X149500Y578600D03*
X164600Y608500D03*
X150500Y699200D03*
G54D51*
X80200Y1477500D03*
X107600Y558300D03*
X115200D03*
X87800Y1477500D03*
X106770Y1480640D03*
X99170D03*
X183700Y1606500D03*
X180700Y1641000D03*
X191300Y1606500D03*
X188300Y1641000D03*
G54D60*
X93206Y677415D03*
Y682415D03*
Y687415D03*
Y692415D03*
X113306D03*
Y687415D03*
Y682415D03*
Y677415D03*
G54D33*
X67998Y53103D03*
X67398Y67603D03*
X61000Y236600D03*
X61600Y207900D03*
X60600Y191600D03*
X54300Y259900D03*
X58300D03*
X37200Y253500D03*
X62600Y245800D03*
X73700Y539900D03*
X78600Y571100D03*
X73900Y555400D03*
X39000Y577900D03*
X77200Y702500D03*
X77000Y727400D03*
X43400Y892700D03*
X81398Y1122703D03*
X63498Y1120403D03*
X63198Y1138603D03*
X48300Y1752300D03*
X116800Y585196D03*
X128900D03*
X91300Y569800D03*
X129335Y658629D03*
X104900Y658800D03*
X115600Y656800D03*
X116300Y667200D03*
X119600Y828400D03*
X111200D03*
X102900Y828396D03*
X121671Y936356D03*
X117300Y936300D03*
X110500D03*
X131500Y944400D03*
X123300Y997900D03*
X119300D03*
X114800D03*
X99000Y976300D03*
X123000Y1420800D03*
X127500D03*
X95500Y1460800D03*
X118000Y1420800D03*
X95600Y1420300D03*
X129000Y1498300D03*
X125000D03*
X121000D03*
X117000D03*
X113000D03*
X109000D03*
X93500Y1475800D03*
X136779Y539671D03*
X145300Y578800D03*
X153500Y566600D03*
X136679Y553771D03*
X151335Y632429D03*
X148435Y649929D03*
X144235D03*
X133535Y658629D03*
X154500Y699300D03*
X167700Y696200D03*
X158500Y699300D03*
X149000Y945800D03*
X153000D03*
X157000D03*
X145000D03*
X140500Y944400D03*
X136000D03*
X139100Y999700D03*
X135000Y999800D03*
X156631Y1427681D03*
X160831Y1426881D03*
X152331Y1427681D03*
X165400Y1426800D03*
X151000Y1487800D03*
X146500D03*
X142000D03*
X137000Y1498300D03*
X133000D03*
X137900Y1487700D03*
X148500Y1470700D03*
G54D24*
X32359Y1680500D03*
X60641D03*
G54D16*
X29100Y321300D03*
X30100Y1083600D03*
X18600Y1644300D03*
X18400Y1720700D03*
X20200Y1692800D03*
X56900Y155300D03*
Y163300D03*
Y179300D03*
Y159300D03*
Y175300D03*
X46500Y213400D03*
X57800Y217000D03*
X56900Y199300D03*
X32800Y272300D03*
X70800Y431300D03*
X61000Y577200D03*
X78556Y690465D03*
X80700Y686400D03*
X45400Y916400D03*
X68700Y999800D03*
X49400Y1769800D03*
X88303Y61502D03*
X85800Y71500D03*
X117900Y437500D03*
X125956Y692165D03*
X125856Y688065D03*
Y683665D03*
X112900Y670600D03*
X83996Y848500D03*
Y844100D03*
Y852900D03*
X84000Y865700D03*
Y857200D03*
Y861500D03*
X111900Y1408200D03*
X91300Y1451000D03*
X109700Y1425900D03*
X91300Y1439000D03*
X84300Y1484000D03*
X128800Y1482000D03*
X159900Y545600D03*
X162700Y622700D03*
X152329Y615065D03*
X171800Y701100D03*
X152096Y1415000D03*
X140500Y1458400D03*
X152100Y1423400D03*
X152096Y1419200D03*
X190800Y439500D03*
G54D43*
X35000Y584900D03*
X58100Y1034400D03*
X87400Y577700D03*
X149500Y582200D03*
X164600Y612100D03*
X150500Y702800D03*
G54D52*
X78900Y1498700D03*
Y1523500D03*
X124298Y1908303D03*
Y1883503D03*
X145798Y1151303D03*
Y1126503D03*
G54D61*
X134709Y710500D03*
X117291D03*
G54D70*
X141100Y1401696D03*
Y1410096D03*
X158600Y1446404D03*
Y1438004D03*
G54D25*
X28000Y1769900D03*
X75700Y71500D03*
X58200Y662300D03*
Y657600D03*
X48700Y1764700D03*
X110200Y769100D03*
Y764100D03*
X99700Y1058400D03*
Y1053700D03*
X182300Y1652700D03*
Y1648000D03*
X141847Y1878698D03*
X141800Y1883700D03*
G54D34*
X71802Y56547D03*
X71400Y71754D03*
X75200Y741500D03*
X75700Y719100D03*
X53800Y1013100D03*
X103500Y597500D03*
X146365Y611321D03*
G54D71*
X147500Y1437250D03*
X143625Y1444750D03*
X151375D03*
G54D17*
X22900Y397800D03*
Y418300D03*
X19100Y667000D03*
X81100Y398500D03*
X47700Y397800D03*
X81100Y419000D03*
X47700Y418300D03*
X43900Y667000D03*
X73600Y798400D03*
X63700Y1090600D03*
X36600Y1551500D03*
X61400D03*
X113100Y88500D03*
X105900Y398500D03*
Y419000D03*
X98400Y798400D03*
X88500Y1090600D03*
X137900Y88500D03*
X185300Y397900D03*
X160500D03*
X185200Y356700D03*
X160400D03*
X185400Y376900D03*
X160600D03*
X185300Y418400D03*
X160500D03*
X184900Y1531500D03*
X160100D03*
X185000Y1551600D03*
X160200D03*
G54D53*
X71250Y1613297D03*
Y1619703D03*
X101750Y1613297D03*
Y1619703D03*
X130250Y1613297D03*
Y1619703D03*
X157750Y1613297D03*
Y1619703D03*
G54D26*
X21350Y1781000D03*
X77953Y54502D03*
X71650Y584000D03*
X58350D03*
X45050Y593000D03*
X58350D03*
X81850Y715400D03*
X81350Y740400D03*
X60150Y1011800D03*
X73450D03*
X64450Y1032100D03*
X77750D03*
X34650Y1781000D03*
X91253Y54502D03*
X95850Y68500D03*
X109150D03*
X95150Y715400D03*
X94650Y740400D03*
G54D62*
X116175Y846304D03*
X113620D03*
X111060D03*
X108500D03*
X105940D03*
X103380D03*
X100825D03*
Y868504D03*
X103380D03*
X105940D03*
X108500D03*
X111060D03*
X113620D03*
X116175D03*
X113960Y985200D03*
X116520D03*
X119080D03*
X121640D03*
Y963000D03*
X119080D03*
X116520D03*
X113960D03*
X155825Y732304D03*
X158380D03*
X160940D03*
X163500D03*
X166060D03*
X168620D03*
X171175D03*
Y710104D03*
X168620D03*
X166060D03*
X163500D03*
X160940D03*
X158380D03*
X155825D03*
X137340Y959500D03*
X139900D03*
X142460D03*
X145020D03*
X147580D03*
X150140D03*
X152700D03*
X155260D03*
Y981700D03*
X152700D03*
X150140D03*
X147580D03*
X145020D03*
X142460D03*
X139900D03*
X137340D03*
G54D35*
X71802Y52947D03*
X71400Y68154D03*
X75200Y737900D03*
X75700Y715500D03*
X53800Y1009500D03*
X103500Y593900D03*
X146365Y607721D03*
G54D44*
X73403Y633502D03*
Y606702D03*
X122097Y1125298D03*
Y1152098D03*
X98497Y1883198D03*
Y1909998D03*
G54D27*
X30300Y1787800D03*
X64500Y573000D03*
X71200Y1144500D03*
X81900Y966200D03*
X87000Y1143000D03*
X94800Y1431500D03*
Y1434900D03*
Y1442800D03*
X163400Y549300D03*
X144300Y695500D03*
X133300Y1432000D03*
G54D45*
X66875Y674606D03*
X69435D03*
X71995D03*
Y681106D03*
X66875D03*
G54D63*
X113800Y1397140D03*
Y1399700D03*
Y1402260D03*
X106400D03*
Y1399700D03*
Y1397140D03*
G54D72*
X142300Y1471800D03*
Y1480800D03*
G54D54*
X48200Y1760300D03*
X86800Y537800D03*
X96100D03*
X98600Y553300D03*
X107600Y593700D03*
X112900Y603500D03*
X170600Y536400D03*
X160900Y536500D03*
G54D36*
X47498Y238899D03*
X52200Y238900D03*
X62700Y254200D03*
X45100Y577300D03*
X81500Y727600D03*
X63202Y1128347D03*
X103900Y476600D03*
X96300Y557700D03*
X129065Y673094D03*
X123465D03*
X124900Y722600D03*
X94500Y976700D03*
X130800Y975800D03*
X146700Y476700D03*
X163300Y696500D03*
X144300Y1111300D03*
X149002Y1111347D03*
X133500Y1471200D03*
G54D18*
X30000Y570800D03*
X24300Y1106000D03*
X18600Y1640200D03*
X19900Y1769600D03*
X67300Y63500D03*
X56900Y171300D03*
Y183300D03*
Y167300D03*
Y187300D03*
X57800Y221000D03*
X46500Y217400D03*
X32682Y264217D03*
X56900Y280000D03*
X78544Y694635D03*
X80000Y682200D03*
X65300Y730000D03*
X68700Y1004300D03*
X59600Y1020600D03*
X72300Y1025400D03*
X72400Y1020900D03*
X38000Y1096000D03*
X68800Y1175100D03*
X30700Y1774400D03*
X35000Y1788200D03*
X98700Y549600D03*
X83700Y569900D03*
X91300Y671000D03*
X115600Y660200D03*
X104900Y662200D03*
X87800Y707900D03*
X86300Y733400D03*
X104100Y1408100D03*
X129800Y1428300D03*
X91300Y1446500D03*
X109700Y1421600D03*
X150100Y430800D03*
X145300Y568000D03*
X152800Y587000D03*
X162700Y626700D03*
X174300Y624300D03*
X148004Y1394000D03*
X140500Y1466400D03*
Y1462400D03*
X140200Y1453300D03*
X157300Y1458000D03*
G54D73*
G01X-448201Y-82763D02*
Y-162763D01*
G01Y-118263D02*
X752899D01*
G01X-448201Y-162763D02*
X752899D01*
G01X-452201Y-66763D02*
G02I-12000J0D01*
G01X-457351D02*
G02I-6850J0D01*
G01X-464201Y-82763D02*
Y-50763D01*
G01X-448201Y-66763D02*
X-480201D01*
G01X-448201Y-82763D02*
X752899D01*
G01X-34601D02*
Y-162763D01*
G01X102899Y-82763D02*
Y-162763D01*
G01X217899Y-82763D02*
Y-162763D01*
G01X385399Y-82763D02*
Y-162763D01*
G01X555399Y-82763D02*
Y-162763D01*
G01X752899Y-82763D02*
Y-162763D01*
G01X780899Y-66763D02*
G02I-12000J0D01*
G01X775749D02*
G02I-6850J0D01*
G01X768899Y-82763D02*
Y-50763D01*
G01X784899Y-66763D02*
X752899D01*
G54D19*
X24100Y690900D03*
X28900D03*
X74100Y576200D03*
X65635Y693906D03*
X70535D03*
X82000Y708200D03*
X72200Y711000D03*
X67200D03*
X70800Y981400D03*
X64200Y1004100D03*
X81398Y1137753D03*
X92300Y878454D03*
X87500D03*
X94000Y962800D03*
X103500Y979800D03*
X129900Y992500D03*
X140400Y572400D03*
X158535Y609679D03*
G54D28*
X26700Y1787800D03*
X60900Y573000D03*
X78300Y966200D03*
X67600Y1144500D03*
X83400Y1143000D03*
X91200Y1431500D03*
Y1434900D03*
X129700Y1432000D03*
X91200Y1442800D03*
X159800Y549300D03*
X140700Y695500D03*
G54D46*
X51750Y690560D03*
Y688000D03*
Y685440D03*
X58250D03*
Y690560D03*
X36250D03*
Y688000D03*
Y685440D03*
X42750D03*
Y690560D03*
G54D37*
X47498Y244499D03*
X52200Y244500D03*
X62700Y259800D03*
X45100Y582900D03*
X81500Y733200D03*
X63202Y1133947D03*
X103900Y482200D03*
X96300Y563300D03*
X129065Y678694D03*
X123465D03*
X124900Y728200D03*
X94500Y982300D03*
X130800Y981400D03*
X146700Y482300D03*
X163300Y702100D03*
X144300Y1116900D03*
X149002Y1116947D03*
X133500Y1476800D03*
G54D55*
X51800Y1760300D03*
X90400Y537800D03*
X99700D03*
X102200Y553300D03*
X111200Y593700D03*
X116500Y603500D03*
X174200Y536400D03*
X164500Y536500D03*
G54D64*
X125000Y1409454D03*
X121125Y1401954D03*
X128875D03*
G54D74*
G01X-430254Y-152763D02*
Y-135263D01*
G01X-421958D02*
X-430254Y-146055D01*
G01X-420648Y-152763D02*
X-426543Y-141097D01*
G01X-412973Y-152763D02*
Y-135263D01*
X-402929Y-152763D01*
Y-135263D01*
G01X-390451Y-152763D02*
X-392198Y-152471D01*
X-393726Y-151305D01*
X-395036Y-149555D01*
X-395910Y-147513D01*
X-396346Y-145180D01*
Y-142846D01*
X-395910Y-140513D01*
X-395036Y-138471D01*
X-393726Y-136722D01*
X-392198Y-135555D01*
X-390451Y-135263D01*
X-388705Y-135555D01*
X-387176Y-136722D01*
X-385866Y-138471D01*
X-384992Y-140513D01*
X-384556Y-142846D01*
Y-145180D01*
X-384992Y-147513D01*
X-385866Y-149555D01*
X-387176Y-151305D01*
X-388705Y-152471D01*
X-390451Y-152763D01*
G01X-377536D02*
X-368366Y-135263D01*
G01X-377536D02*
X-368366Y-152763D01*
G01X-362001Y-158596D02*
X-348901D01*
G01X-342099Y-152763D02*
Y-135263D01*
X-333803D01*
G01X-336859Y-143721D02*
X-342099D01*
G01X-325910Y-152763D02*
X-320451Y-135263D01*
X-314992Y-152763D01*
G01X-316958Y-146638D02*
X-323945D01*
G01X-307973Y-152763D02*
Y-135263D01*
X-297929Y-152763D01*
Y-135263D01*
G01X-263148Y-136722D02*
X-264458Y-135846D01*
X-265986Y-135263D01*
X-267733D01*
X-269698Y-136138D01*
X-271226Y-137596D01*
X-272318Y-139347D01*
X-273191Y-142263D01*
X-273410Y-144888D01*
X-272973Y-147513D01*
X-272318Y-149263D01*
X-271008Y-151013D01*
X-269479Y-152180D01*
X-267951Y-152763D01*
X-266423D01*
X-264894Y-152180D01*
X-263584Y-151305D01*
X-262492Y-150139D01*
G01X-250451Y-152763D02*
X-252198Y-152471D01*
X-253726Y-151305D01*
X-255036Y-149555D01*
X-255910Y-147513D01*
X-256346Y-145180D01*
Y-142846D01*
X-255910Y-140513D01*
X-255036Y-138471D01*
X-253726Y-136722D01*
X-252198Y-135555D01*
X-250451Y-135263D01*
X-248705Y-135555D01*
X-247176Y-136722D01*
X-245866Y-138471D01*
X-244992Y-140513D01*
X-244556Y-142846D01*
Y-145180D01*
X-244992Y-147513D01*
X-245866Y-149555D01*
X-247176Y-151305D01*
X-248705Y-152471D01*
X-250451Y-152763D01*
G01X-237973D02*
Y-135263D01*
X-227929Y-152763D01*
Y-135263D01*
G01X-215451D02*
Y-152763D01*
G01X-220473Y-135263D02*
X-210429D01*
G01X-202318Y-152763D02*
Y-135263D01*
X-196859D01*
X-195113Y-136138D01*
X-194021Y-137305D01*
X-193584Y-139638D01*
X-194021Y-141972D01*
X-195331Y-143430D01*
X-196859Y-144305D01*
X-202318D01*
G01X-196859D02*
X-193584Y-152763D01*
G01X-180451D02*
X-182198Y-152471D01*
X-183726Y-151305D01*
X-185036Y-149555D01*
X-185910Y-147513D01*
X-186346Y-145180D01*
Y-142846D01*
X-185910Y-140513D01*
X-185036Y-138471D01*
X-183726Y-136722D01*
X-182198Y-135555D01*
X-180451Y-135263D01*
X-178705Y-135555D01*
X-177176Y-136722D01*
X-175866Y-138471D01*
X-174992Y-140513D01*
X-174556Y-142846D01*
Y-145180D01*
X-174992Y-147513D01*
X-175866Y-149555D01*
X-177176Y-151305D01*
X-178705Y-152471D01*
X-180451Y-152763D01*
G01X-167318Y-135263D02*
Y-152763D01*
X-158584D01*
G01X-126205Y-143430D02*
X-125331Y-142555D01*
X-124676Y-141097D01*
X-124239Y-139054D01*
X-124676Y-137305D01*
X-125549Y-136138D01*
X-127078Y-135263D01*
X-132973D01*
Y-152763D01*
X-125768D01*
X-124239Y-151597D01*
X-123366Y-149846D01*
X-122929Y-147805D01*
X-123366Y-145763D01*
X-124676Y-144013D01*
X-126205Y-143430D01*
X-132973D01*
G01X-110451Y-152763D02*
X-112198Y-152471D01*
X-113726Y-151305D01*
X-115036Y-149555D01*
X-115910Y-147513D01*
X-116346Y-145180D01*
Y-142846D01*
X-115910Y-140513D01*
X-115036Y-138471D01*
X-113726Y-136722D01*
X-112198Y-135555D01*
X-110451Y-135263D01*
X-108705Y-135555D01*
X-107176Y-136722D01*
X-105866Y-138471D01*
X-104992Y-140513D01*
X-104556Y-142846D01*
Y-145180D01*
X-104992Y-147513D01*
X-105866Y-149555D01*
X-107176Y-151305D01*
X-108705Y-152471D01*
X-110451Y-152763D01*
G01X-98410D02*
X-92951Y-135263D01*
X-87492Y-152763D01*
G01X-89458Y-146638D02*
X-96445D01*
G01X-79818Y-152763D02*
Y-135263D01*
X-74359D01*
X-72613Y-136138D01*
X-71521Y-137305D01*
X-71084Y-139638D01*
X-71521Y-141972D01*
X-72831Y-143430D01*
X-74359Y-144305D01*
X-79818D01*
G01X-74359D02*
X-71084Y-152763D01*
G01X-62754D02*
Y-135263D01*
X-58388D01*
X-56641Y-136138D01*
X-55331Y-137305D01*
X-54239Y-139054D01*
X-53366Y-141097D01*
X-53148Y-144013D01*
X-53366Y-146930D01*
X-54239Y-148972D01*
X-55331Y-150722D01*
X-56641Y-151888D01*
X-58388Y-152763D01*
X-62754D01*
G01X-282378Y-107763D02*
Y-90263D01*
X-276701Y-104846D01*
X-271024Y-90263D01*
Y-107763D01*
G01X-259201D02*
X-260511Y-107471D01*
X-261821Y-106305D01*
X-262695Y-104263D01*
X-263131Y-101930D01*
X-262695Y-99596D01*
X-261821Y-97555D01*
X-260511Y-96388D01*
X-259201Y-96097D01*
X-257891Y-96388D01*
X-256581Y-97555D01*
X-255708Y-99596D01*
X-255489Y-101930D01*
X-255708Y-104263D01*
X-256581Y-106305D01*
X-257891Y-107471D01*
X-259201Y-107763D01*
G01X-237771Y-90263D02*
Y-107763D01*
G01Y-105139D02*
X-238644Y-106597D01*
X-239955Y-107471D01*
X-241483Y-107763D01*
X-243229Y-107180D01*
X-244539Y-105722D01*
X-245413Y-103972D01*
X-245631Y-101930D01*
X-245413Y-99888D01*
X-244539Y-98138D01*
X-243229Y-96680D01*
X-241483Y-96097D01*
X-239955Y-96388D01*
X-238863Y-96972D01*
X-237771Y-98138D01*
G01X-227476Y-99888D02*
X-220489D01*
X-221144Y-97846D01*
X-222236Y-96680D01*
X-223764Y-96097D01*
X-225293Y-96388D01*
X-226603Y-97263D01*
X-227476Y-99305D01*
X-227913Y-101055D01*
Y-102805D01*
X-227476Y-104555D01*
X-226384Y-106305D01*
X-225074Y-107471D01*
X-223546Y-107763D01*
X-222018Y-107180D01*
X-220489Y-105430D01*
G01X-206701Y-107763D02*
Y-90263D01*
G01X-242126Y15000D02*
G03X-227126Y0I15000J0D01*
G01X-242126Y1953504D02*
Y15000D01*
G01X-215453Y19685D02*
G03I-6988J0D01*
G01X-84646Y0D02*
X-227126D01*
G01X-215453Y19685D02*
G03I-6988J0D01*
G01D02*
G03I-6988J0D01*
G01X-227126Y1968504D02*
G03X-242126Y1953504I0J-15000D01*
G01X-215453Y1948819D02*
G03I-6988J0D01*
G01X-84638Y1968504D02*
X-227126D01*
G01X-215453Y1948819D02*
G03I-6988J0D01*
G01D02*
G03I-6988J0D01*
G01X-222441Y39370D02*
G03X-214567Y31496I7874J0D01*
G01X-206693D02*
X-214567D01*
G01X-175984D02*
X-84646D01*
G01X-206693D02*
G03Y39370I0J3937D01*
G01X-175984D02*
G03Y31496I0J-3937D01*
G01X-206693D02*
X-214567D01*
G01X-84646Y0D02*
X-199567D01*
G01X-175984Y31496D02*
X-84646D01*
G01X-206693D02*
G03Y39370I0J3937D01*
G01X-175984D02*
G03Y31496I0J-3937D01*
G01X-222441Y169326D02*
Y39370D01*
G01X-214567Y43307D02*
G03X-210630Y39370I3937J0D01*
G01X-214567Y43307D02*
G03X-210630Y39370I3937J0D01*
G01X-80709D02*
X-210630D01*
G01X-80709D02*
X-210630D01*
G01X-214567Y43307D02*
Y1925197D01*
G01Y43307D02*
Y1925197D01*
G01Y149606D02*
Y43307D01*
G01Y149606D02*
Y43272D01*
G01Y169326D02*
G03X-222441I-3937J0D01*
G01X-214567D02*
G03X-222441I-3937J0D01*
G01X-214567Y1807087D02*
Y161417D01*
G01Y1807087D02*
Y161417D01*
G01X-222441Y436255D02*
Y200034D01*
G01D02*
G03X-214567I3937J0D01*
G01X-222441D02*
G03X-214567I3937J0D01*
G01Y436255D02*
G03X-222441I-3937J0D01*
G01X-214567D02*
G03X-222441I-3937J0D01*
G01Y703184D02*
Y466963D01*
G01D02*
G03X-214567I3937J0D01*
G01X-222441D02*
G03X-214567I3937J0D01*
G01X-222441Y970901D02*
Y733892D01*
G01X-214567Y703184D02*
G03X-222441I-3937J0D01*
G01Y733892D02*
G03X-214567I3937J0D01*
G01Y703184D02*
G03X-222441I-3937J0D01*
G01Y733892D02*
G03X-214567I3937J0D01*
G01X-222441Y1234681D02*
Y997672D01*
G01X-214567Y970901D02*
G03X-222441I-3937J0D01*
G01Y997672D02*
G03X-214567I3937J0D01*
G01Y970901D02*
G03X-222441I-3937J0D01*
G01Y997672D02*
G03X-214567I3937J0D01*
G01X-222441Y1265389D02*
G03X-214567I3937J0D01*
G01Y1234681D02*
G03X-222441I-3937J0D01*
G01Y1265389D02*
G03X-214567I3937J0D01*
G01Y1234681D02*
G03X-222441I-3937J0D01*
G01Y1501610D02*
Y1265389D01*
G01X-214567Y1501610D02*
G03X-222441I-3937J0D01*
G01X-214567D02*
G03X-222441I-3937J0D01*
G01Y1768539D02*
Y1532318D01*
G01D02*
G03X-214567I3937J0D01*
G01X-222441D02*
G03X-214567I3937J0D01*
G01Y1768539D02*
G03X-222441I-3937J0D01*
G01X-214567D02*
G03X-222441I-3937J0D01*
G01Y1799247D02*
G03X-214567I3937J0D01*
G01X-222441D02*
G03X-214567I3937J0D01*
G01X-222441Y1929134D02*
Y1799247D01*
G01X-214567Y1818898D02*
Y1925231D01*
G01Y1818898D02*
Y1925231D01*
G01X-210630Y1929134D02*
G03X-214567Y1925197I0J-3937D01*
G01X-210630Y1929134D02*
G03X-214567Y1925197I0J-3937D01*
G01Y1937008D02*
G03X-222441Y1929134I0J-7874D01*
G01X-210630D02*
X-80709D01*
G01X-210630D02*
X-80709D01*
G01X-175984Y1937008D02*
X-84638D01*
G01X-214567D02*
X-206693D01*
G01X-175984D02*
G03Y1929134I0J-3937D01*
G01X-206693D02*
G03Y1937008I0J3937D01*
G01X-84638Y1968504D02*
X-199567D01*
G01X-175984Y1937008D02*
X-84638D01*
G01X-214567D02*
X-206693D01*
G01X-175984D02*
G03Y1929134I0J-3937D01*
G01X-206693D02*
G03Y1937008I0J3937D01*
G01X-76772Y3937D02*
G03X-72835Y0I3937J0D01*
G01X-76772Y35433D02*
G03X-80709Y39370I-3937J0D01*
G01X-76772Y35433D02*
G03X-80709Y39370I-3937J0D01*
G01X-76772Y3937D02*
G03X-72835Y0I3937J0D01*
G01X-76772Y3937D02*
Y35433D01*
G01Y3937D02*
Y35433D01*
G01Y3937D02*
G03X-72835Y0I3937J0D01*
G01X-84646Y7874D02*
Y0D01*
G01X-76772Y7874D02*
G03X-84646I-3937J0D01*
G01Y31496D02*
G03X-76772I3937J0D01*
G01Y3937D02*
G03X-72835Y0I3937J0D01*
G01X-84646Y7874D02*
Y0D01*
G01X-76772Y7874D02*
G03X-84646I-3937J0D01*
G01Y31496D02*
G03X-76772I3937J0D01*
G01X-76763Y1937008D02*
G03X-84638I-3937J0D01*
G01X-80709Y1929134D02*
G03X-76772Y1933071I0J3937D01*
G01X-80709Y1929134D02*
G03X-76772Y1933071I0J3937D01*
G01X-72835Y1968504D02*
G03X-76772Y1964567I0J-3937D01*
G01X-72835Y1968504D02*
G03X-76772Y1964567I0J-3937D01*
G01Y1933071D02*
Y1964567D01*
G01Y1933071D02*
Y1964567D01*
G01X-72835Y1968504D02*
G03X-76772Y1964567I0J-3937D01*
G01X-84638Y1960889D02*
Y1968504D01*
G01Y1960889D02*
G03X-76763I3938J0D01*
G01X-72835Y1968504D02*
G03X-76772Y1964567I0J-3937D01*
G01X-84638Y1960889D02*
Y1968504D01*
G01Y1960889D02*
G03X-76763I3938J0D01*
G01X-11811Y0D02*
X-72835D01*
G01X-11811D02*
X-72835D01*
G01D02*
X-11811D01*
G01X-72835D02*
X-11811D01*
G01X-72835Y1968504D02*
X-11811D01*
G01X-72835D02*
X-11811D01*
G01D02*
X-72835D01*
G01X-11811D02*
X-72835D01*
G01X-901Y-152763D02*
Y-135263D01*
X-3521Y-138763D01*
G01Y-152763D02*
X1719D01*
G01X12451Y-138180D02*
X13761Y-136430D01*
X15289Y-135555D01*
X17036Y-135263D01*
X19219Y-135846D01*
X20747Y-137305D01*
X21184Y-139054D01*
X20966Y-140805D01*
X20092Y-142263D01*
X15726Y-145180D01*
X13761Y-147221D01*
X12451Y-150139D01*
X12014Y-152763D01*
X21184D01*
G01X36719D02*
Y-135263D01*
X28640Y-147805D01*
X39558D01*
G01X46796Y-149263D02*
X48105Y-151305D01*
X49852Y-152471D01*
X51817Y-152763D01*
X53564Y-152471D01*
X55311Y-151013D01*
X56402Y-149263D01*
X56621Y-147513D01*
X56184Y-145472D01*
X54656Y-144013D01*
X53127Y-143430D01*
X51162D01*
G01X53127D02*
X54437Y-142555D01*
X55529Y-141097D01*
X55966Y-139347D01*
X55529Y-137596D01*
X54437Y-136138D01*
X52472Y-135263D01*
X50507Y-135555D01*
X48542Y-136722D01*
G01X64296Y-149263D02*
X65605Y-151305D01*
X67352Y-152471D01*
X69317Y-152763D01*
X71064Y-152471D01*
X72811Y-151013D01*
X73902Y-149263D01*
X74121Y-147513D01*
X73684Y-145472D01*
X72156Y-144013D01*
X70627Y-143430D01*
X68662D01*
G01X70627D02*
X71937Y-142555D01*
X73029Y-141097D01*
X73466Y-139347D01*
X73029Y-137596D01*
X71937Y-136138D01*
X69972Y-135263D01*
X68007Y-135555D01*
X66042Y-136722D01*
G01X-14018Y-107763D02*
Y-90263D01*
X-8778D01*
X-7031Y-91138D01*
X-5721Y-93180D01*
X-5284Y-95513D01*
X-5721Y-97846D01*
X-6813Y-99596D01*
X-8778Y-100472D01*
X-14018D01*
G01X12652Y-91722D02*
X11342Y-90846D01*
X9814Y-90263D01*
X8067D01*
X6102Y-91138D01*
X4574Y-92596D01*
X3482Y-94347D01*
X2609Y-97263D01*
X2390Y-99888D01*
X2827Y-102513D01*
X3482Y-104263D01*
X4792Y-106013D01*
X6321Y-107180D01*
X7849Y-107763D01*
X9377D01*
X10906Y-107180D01*
X12216Y-106305D01*
X13308Y-105139D01*
G01X27095Y-98430D02*
X27969Y-97555D01*
X28624Y-96097D01*
X29061Y-94054D01*
X28624Y-92305D01*
X27751Y-91138D01*
X26222Y-90263D01*
X20327D01*
Y-107763D01*
X27532D01*
X29061Y-106597D01*
X29934Y-104846D01*
X30371Y-102805D01*
X29934Y-100763D01*
X28624Y-99013D01*
X27095Y-98430D01*
X20327D01*
G01X36299Y-113596D02*
X49399D01*
G01X55327Y-107763D02*
Y-90263D01*
X65371Y-107763D01*
Y-90263D01*
G01X77849Y-107763D02*
X76102Y-107471D01*
X74574Y-106305D01*
X73264Y-104555D01*
X72390Y-102513D01*
X71954Y-100180D01*
Y-97846D01*
X72390Y-95513D01*
X73264Y-93471D01*
X74574Y-91722D01*
X76102Y-90555D01*
X77849Y-90263D01*
X79595Y-90555D01*
X81124Y-91722D01*
X82434Y-93471D01*
X83308Y-95513D01*
X83744Y-97846D01*
Y-100180D01*
X83308Y-102513D01*
X82434Y-104555D01*
X81124Y-106305D01*
X79595Y-107471D01*
X77849Y-107763D01*
G01X-11811Y0D02*
G03X-7874Y3937I0J3937D01*
G01X-11811Y0D02*
G03X-7874Y3937I0J3937D01*
G01Y43110D02*
Y3937D01*
G01Y43110D02*
Y3937D01*
G01X0D02*
G03X3937Y0I3937J0D01*
G01X0Y3937D02*
G03X3937Y0I3937J0D01*
G01X0Y3937D02*
Y43110D01*
G01Y3937D02*
Y43110D01*
G01X64961Y0D02*
X3937D01*
G01X64961D02*
X3937D01*
G01X0Y3937D02*
G03X3937Y0I3937J0D01*
G01X0Y1964567D02*
Y3937D01*
G01X3937Y0D02*
X64961D01*
G01X-7874Y3937D02*
Y1964567D01*
G01X-11811Y0D02*
G03X-7874Y3937I0J3937D01*
G01X0Y11811D02*
G03X-7874I-3937J0D01*
G01X0Y3937D02*
G03X3937Y0I3937J0D01*
G01X0Y1964567D02*
Y3937D01*
G01X3937Y0D02*
X64961D01*
G01X-7874Y3937D02*
Y1964567D01*
G01X-11811Y0D02*
G03X-7874Y3937I0J3937D01*
G01X0Y11811D02*
G03X-7874I-3937J0D01*
G01Y93110D02*
Y43110D01*
G01Y93110D02*
Y43110D01*
G01X0D02*
Y93110D01*
G01Y43110D02*
Y93110D01*
G01X-7874Y42520D02*
G03X0I3937J0D01*
G01X-7874D02*
G03X0I3937J0D01*
G01X-7874Y214764D02*
Y93110D01*
G01Y214764D02*
Y93110D01*
G01X0D02*
Y214764D01*
G01Y93110D02*
Y214764D01*
G01X-7874Y226968D02*
Y214764D01*
G01Y226968D02*
Y214764D01*
G01Y342461D02*
Y226968D01*
G01Y342461D02*
Y226968D01*
G01X0Y226969D02*
Y342461D01*
G01Y226969D02*
Y342461D01*
G01Y214764D02*
Y226969D01*
G01Y214764D02*
Y226969D01*
G01Y278740D02*
G03X-7874I-3937J0D01*
G01X0D02*
G03X-7874I-3937J0D01*
G01Y354665D02*
Y342461D01*
G01Y354665D02*
Y342461D01*
G01X0D02*
Y354665D01*
G01Y342461D02*
Y354665D01*
G01X-7874Y309449D02*
G03X0I3937J0D01*
G01X-7874D02*
G03X0I3937J0D01*
G01X-7874Y476339D02*
Y354665D01*
G01Y476339D02*
Y354665D01*
G01X0D02*
Y476339D01*
G01Y354665D02*
Y476339D01*
G01X-7874Y526339D02*
Y476339D01*
G01Y526339D02*
Y476339D01*
G01X0D02*
Y526339D01*
G01Y476339D02*
Y526339D01*
G01X-7874Y736181D02*
Y526339D01*
G01Y736181D02*
Y526339D01*
G01X0D02*
Y736181D01*
G01Y526339D02*
Y736181D01*
G01Y545669D02*
G03X-7874I-3937J0D01*
G01X0D02*
G03X-7874I-3937J0D01*
G01Y576378D02*
G03X0I3937J0D01*
G01X-7874D02*
G03X0I3937J0D01*
G01X-7874Y786181D02*
Y736181D01*
G01Y786181D02*
Y736181D01*
G01X0D02*
Y786181D01*
G01Y736181D02*
Y786181D01*
G01X-7874Y907815D02*
Y786181D01*
G01Y907815D02*
Y786181D01*
G01X0D02*
Y907815D01*
G01Y786181D02*
Y907815D01*
G01Y831496D02*
G03X-7874I-3937J0D01*
G01X0D02*
G03X-7874I-3937J0D01*
G01Y862205D02*
G03X0I3937J0D01*
G01X-7874D02*
G03X0I3937J0D01*
G01X-7874Y920020D02*
Y907815D01*
G01Y920020D02*
Y907815D01*
G01Y1048484D02*
Y920020D01*
G01Y1048484D02*
Y920020D01*
G01X0D02*
Y1048484D01*
G01Y920020D02*
Y1048484D01*
G01Y907815D02*
Y920020D01*
G01Y907815D02*
Y920020D01*
G01X-7874Y1060689D02*
Y1048484D01*
G01Y1060689D02*
Y1048484D01*
G01X0D02*
Y1060689D01*
G01Y1048484D02*
Y1060689D01*
G01X-7874Y1182323D02*
Y1060689D01*
G01Y1182323D02*
Y1060689D01*
G01X0D02*
Y1182323D01*
G01Y1060689D02*
Y1182323D01*
G01Y1106299D02*
G03X-7874I-3937J0D01*
G01X0D02*
G03X-7874I-3937J0D01*
G01Y1137008D02*
G03X0I3937J0D01*
G01X-7874D02*
G03X0I3937J0D01*
G01X-7874Y1232323D02*
Y1182323D01*
G01Y1232323D02*
Y1182323D01*
G01X0D02*
Y1232323D01*
G01Y1182323D02*
Y1232323D01*
G01X-7874Y1442165D02*
Y1232323D01*
G01Y1442165D02*
Y1232323D01*
G01X0D02*
Y1442165D01*
G01Y1232323D02*
Y1442165D01*
G01Y1392126D02*
G03X-7874I-3937J0D01*
G01X0D02*
G03X-7874I-3937J0D01*
G01Y1492165D02*
Y1442165D01*
G01Y1492165D02*
Y1442165D01*
G01X0D02*
Y1492165D01*
G01Y1442165D02*
Y1492165D01*
G01X-7874Y1422835D02*
G03X0I3937J0D01*
G01X-7874D02*
G03X0I3937J0D01*
G01X-7874Y1613839D02*
Y1492165D01*
G01Y1613839D02*
Y1492165D01*
G01X0D02*
Y1613839D01*
G01Y1492165D02*
Y1613839D01*
G01X-7874Y1626043D02*
Y1613839D01*
G01Y1626043D02*
Y1613839D01*
G01X0D02*
Y1626043D01*
G01Y1613839D02*
Y1626043D01*
G01X-7874Y1741535D02*
Y1626043D01*
G01Y1741535D02*
Y1626043D01*
G01X0D02*
Y1741535D01*
G01Y1626043D02*
Y1741535D01*
G01Y1659055D02*
G03X-7874I-3937J0D01*
G01X0D02*
G03X-7874I-3937J0D01*
G01Y1689764D02*
G03X0I3937J0D01*
G01X-7874D02*
G03X0I3937J0D01*
G01X-7874Y1753740D02*
Y1741535D01*
G01Y1753740D02*
Y1741535D01*
G01Y1875394D02*
Y1753740D01*
G01Y1875394D02*
Y1753740D01*
G01X0D02*
Y1875394D01*
G01Y1753740D02*
Y1875394D01*
G01Y1741535D02*
Y1753740D01*
G01Y1741535D02*
Y1753740D01*
G01X-7874Y1925394D02*
Y1875394D01*
G01Y1925394D02*
Y1875394D01*
G01X0D02*
Y1925394D01*
G01Y1875394D02*
Y1925394D01*
G01X-7874Y1964567D02*
Y1925394D01*
G01Y1964567D02*
Y1925394D01*
G01X0D02*
Y1964567D01*
G01Y1925394D02*
Y1964567D01*
G01Y1925984D02*
G03X-7874I-3937J0D01*
G01X0D02*
G03X-7874I-3937J0D01*
G01Y1964567D02*
G03X-11811Y1968504I-3937J0D01*
G01X-7874Y1964567D02*
G03X-11811Y1968504I-3937J0D01*
G01X3937D02*
G03X0Y1964567I0J-3937D01*
G01X3937Y1968504D02*
G03X0Y1964567I0J-3937D01*
G01X3937Y1968504D02*
X64961D01*
G01X3937D02*
X64961D01*
G01X3937D02*
G03X0Y1964567I0J-3937D01*
G01X64961Y1968504D02*
X3937D01*
G01X-7874Y1964567D02*
G03X-11811Y1968504I-3937J0D01*
G01X-7874Y1956693D02*
G03X0I3937J0D01*
G01X3937Y1968504D02*
G03X0Y1964567I0J-3937D01*
G01X64961Y1968504D02*
X3937D01*
G01X-7874Y1964567D02*
G03X-11811Y1968504I-3937J0D01*
G01X-7874Y1956693D02*
G03X0I3937J0D01*
G01X168110Y31496D02*
X76763D01*
G01X72835Y39370D02*
G03X68898Y35433I0J-3937D01*
G01X72835Y39370D02*
G03X68898Y35433I0J-3937D01*
G01X64961Y0D02*
G03X68898Y3937I0J3937D01*
G01X64961Y0D02*
G03X68898Y3937I0J3937D01*
G01Y35433D02*
Y3937D01*
G01Y35433D02*
Y3937D01*
G01X72835Y39370D02*
G03X68898Y35433I0J-3937D01*
G01Y3937D02*
Y35485D01*
G01X64961Y0D02*
G03X68898Y3937I0J3937D01*
G01X76763D02*
G03X80700Y0I3937J0D01*
G01X76763Y7615D02*
Y3937D01*
G01X168110Y31496D02*
X76763D01*
G01Y7615D02*
G03X68889I-3937J0D01*
G01Y31496D02*
G03X76763I3937J0D01*
G01X72835Y39370D02*
G03X68898Y35433I0J-3937D01*
G01Y3937D02*
Y35485D01*
G01X64961Y0D02*
G03X68898Y3937I0J3937D01*
G01X76763D02*
G03X80700Y0I3937J0D01*
G01X76763Y7615D02*
Y3937D01*
G01X168110Y31496D02*
X76763D01*
G01Y7615D02*
G03X68889I-3937J0D01*
G01Y31496D02*
G03X76763I3937J0D01*
G01X202756Y39370D02*
X72835D01*
G01X202756D02*
X72835D01*
G01D02*
X202756D01*
G01X72835D02*
X202756D01*
G01X68898Y1964567D02*
G03X64961Y1968504I-3937J0D01*
G01X68898Y1933071D02*
G03X72835Y1929134I3937J0D01*
G01X68898Y1933071D02*
G03X72835Y1929134I3937J0D01*
G01X68898Y1964567D02*
G03X64961Y1968504I-3937J0D01*
G01X72835Y1929134D02*
X202756D01*
G01X72835D02*
X202756D01*
G01X68898Y1964567D02*
Y1933071D01*
G01Y1964567D02*
Y1933071D01*
G01Y1964567D02*
G03X64961Y1968504I-3937J0D01*
G01X68898Y1933071D02*
Y1964567D01*
G01Y1933071D02*
G03X72835Y1929134I3937J0D01*
G01X202756D02*
X72835D01*
G01X80709Y1968504D02*
G03X76772Y1964567I0J-3937D01*
G01Y1960630D02*
Y1964567D01*
G01X168110Y1937008D02*
X76772D01*
G01X68898Y1960630D02*
G03X76772I3937J0D01*
G01Y1937008D02*
G03X68898I-3937J0D01*
G01Y1964567D02*
G03X64961Y1968504I-3937J0D01*
G01X68898Y1933071D02*
Y1964567D01*
G01Y1933071D02*
G03X72835Y1929134I3937J0D01*
G01X202756D02*
X72835D01*
G01X80709Y1968504D02*
G03X76772Y1964567I0J-3937D01*
G01Y1960630D02*
Y1964567D01*
G01X168110Y1937008D02*
X76772D01*
G01X68898Y1960630D02*
G03X76772I3937J0D01*
G01Y1937008D02*
G03X68898I-3937J0D01*
G01X128690Y-90263D02*
X134149Y-107763D01*
X139608Y-90263D01*
G01X156016Y-107763D02*
X147282D01*
Y-90263D01*
X156016D01*
G01X152522Y-98721D02*
X147282D01*
G01X164782Y-107763D02*
Y-90263D01*
X170241D01*
X171987Y-91138D01*
X173079Y-92305D01*
X173516Y-94638D01*
X173079Y-96972D01*
X171769Y-98430D01*
X170241Y-99305D01*
X164782D01*
G01X170241D02*
X173516Y-107763D01*
G01X186649Y-108346D02*
X186212Y-108055D01*
Y-107471D01*
X186649Y-107180D01*
X187086Y-107471D01*
Y-108055D01*
X186649Y-108346D01*
G01X80700Y0D02*
X340551D01*
G01X80700D02*
X340551D01*
G01X118011Y1968504D02*
X142520D01*
G01X109377D02*
X110137D01*
G01X109377D02*
X80709D01*
G01X110137D02*
G03X118011I3937J0D01*
G01X109377D02*
X80709D01*
G01X110137D02*
G03X118011I3937J0D01*
G01X151649Y-152763D02*
Y-135263D01*
X149029Y-138763D01*
G01Y-152763D02*
X154269D01*
G01X163472D02*
Y-135263D01*
X169149Y-149846D01*
X174826Y-135263D01*
Y-152763D01*
G01X168110Y31496D02*
G03Y39370I0J3937D01*
G01Y31496D02*
G03Y39370I0J3937D01*
G01X340559Y1968504D02*
X142520D01*
G01X168110Y1929134D02*
G03Y1937008I0J3937D01*
G01X340559Y1968504D02*
X142520D01*
G01X168110Y1929134D02*
G03Y1937008I0J3937D01*
G01X222441Y31496D02*
X198819D01*
G01X222441D02*
G03Y39370I0J3937D01*
G01X198819D02*
G03Y31496I0J-3937D01*
G01X222441D02*
X198819D01*
G01X222441D02*
G03Y39370I0J3937D01*
G01X198819D02*
G03Y31496I0J-3937D01*
G01X214567Y161417D02*
Y43307D01*
G01X202756Y39370D02*
G03X206693Y43307I0J3937D01*
G01X202756Y39370D02*
G03X206693Y43307I0J3937D01*
G01Y1925197D02*
Y43307D01*
G01Y1925197D02*
Y43307D01*
G01X202756Y39370D02*
G03X206693Y43307I0J3937D01*
G01X218504Y39370D02*
X348425D01*
G01X214567Y43307D02*
G03X218504Y39370I3937J0D01*
G01X202756D02*
G03X206693Y43307I0J3937D01*
G01X218504Y39370D02*
X348425D01*
G01X214567Y43307D02*
G03X218504Y39370I3937J0D01*
G01X206693Y161417D02*
Y1807087D01*
G01X214567D02*
Y161417D01*
G01Y169291D02*
G03X206693I-3937J0D01*
G01Y161417D02*
Y1807087D01*
G01X214567D02*
Y161417D01*
G01Y169291D02*
G03X206693I-3937J0D01*
G01Y200000D02*
G03X214567I3937J0D01*
G01X206693D02*
G03X214567I3937J0D01*
G01Y436220D02*
G03X206693I-3937J0D01*
G01X214567D02*
G03X206693I-3937J0D01*
G01Y466929D02*
G03X214567I3937J0D01*
G01X206693D02*
G03X214567I3937J0D01*
G01Y703149D02*
G03X206693I-3937J0D01*
G01Y733858D02*
G03X214567I3937J0D01*
G01Y703149D02*
G03X206693I-3937J0D01*
G01Y733858D02*
G03X214567I3937J0D01*
G01Y970867D02*
G03X206693I-3937J0D01*
G01Y997637D02*
G03X214567I3937J0D01*
G01Y970867D02*
G03X206693I-3937J0D01*
G01Y997637D02*
G03X214567I3937J0D01*
G01X206693Y1265355D02*
G03X214567I3937J0D01*
G01Y1234646D02*
G03X206693I-3937J0D01*
G01Y1265355D02*
G03X214567I3937J0D01*
G01Y1234646D02*
G03X206693I-3937J0D01*
G01X214567Y1501575D02*
G03X206693I-3937J0D01*
G01X214567D02*
G03X206693I-3937J0D01*
G01Y1532284D02*
G03X214567I3937J0D01*
G01X206693D02*
G03X214567I3937J0D01*
G01Y1768504D02*
G03X206693I-3937J0D01*
G01X214567D02*
G03X206693I-3937J0D01*
G01X214567Y1807087D02*
Y1925197D01*
G01X206693Y1799213D02*
G03X214567I3937J0D01*
G01X206693D02*
G03X214567I3937J0D01*
G01X206693Y1925197D02*
G03X202756Y1929134I-3937J0D01*
G01X206693Y1925197D02*
G03X202756Y1929134I-3937J0D01*
G01X206693Y1925197D02*
G03X202756Y1929134I-3937J0D01*
G01X218504D02*
G03X214567Y1925197I0J-3937D01*
G01X206693D02*
G03X202756Y1929134I-3937J0D01*
G01X218504D02*
G03X214567Y1925197I0J-3937D01*
G01X348425Y1929134D02*
X218504D01*
G01X198819Y1937008D02*
X222441D01*
G01X198819D02*
G03Y1929134I0J-3937D01*
G01X222441D02*
G03Y1937008I0J3937D01*
G01X348425Y1929134D02*
X218504D01*
G01X198819Y1937008D02*
X222441D01*
G01X198819D02*
G03Y1929134I0J-3937D01*
G01X222441D02*
G03Y1937008I0J3937D01*
G01X275349Y-135263D02*
Y-152763D01*
G01X270327Y-135263D02*
X280371D01*
G01X288264Y-150430D02*
X290011Y-151888D01*
X291976Y-152763D01*
X293722D01*
X295469Y-151888D01*
X296779Y-150430D01*
X297434Y-148388D01*
X296997Y-146347D01*
X295906Y-144596D01*
X293941Y-143430D01*
X291321Y-142846D01*
X289792Y-141680D01*
X289137Y-139638D01*
X289574Y-137596D01*
X290666Y-136138D01*
X292194Y-135263D01*
X293722D01*
X295251Y-135846D01*
X296561Y-137305D01*
G01X304672Y-152763D02*
Y-135263D01*
X310349Y-149846D01*
X316026Y-135263D01*
Y-152763D01*
G01X323046D02*
Y-135263D01*
X327412D01*
X329159Y-136138D01*
X330469Y-137305D01*
X331561Y-139054D01*
X332434Y-141097D01*
X332652Y-144013D01*
X332434Y-146930D01*
X331561Y-148972D01*
X330469Y-150722D01*
X329159Y-151888D01*
X327412Y-152763D01*
X323046D01*
G01X253482Y-90263D02*
Y-107763D01*
X262216D01*
G01X279279D02*
Y-96097D01*
G01Y-98138D02*
X278406Y-96972D01*
X277095Y-96388D01*
X275567Y-96097D01*
X274039Y-96680D01*
X272729Y-97846D01*
X271855Y-99596D01*
X271419Y-101930D01*
X271855Y-104263D01*
X272729Y-106013D01*
X274039Y-107180D01*
X275567Y-107763D01*
X277095Y-107471D01*
X278406Y-106597D01*
X279279Y-105430D01*
G01X288264Y-113013D02*
X289574Y-113596D01*
X291321Y-113013D01*
X292412Y-111847D01*
X293286Y-110388D01*
X294595Y-105722D01*
X297434Y-96097D01*
G01X290447D02*
X294595Y-105722D01*
G01X307074Y-99888D02*
X314061D01*
X313406Y-97846D01*
X312314Y-96680D01*
X310786Y-96097D01*
X309257Y-96388D01*
X307947Y-97263D01*
X307074Y-99305D01*
X306637Y-101055D01*
Y-102805D01*
X307074Y-104555D01*
X308166Y-106305D01*
X309476Y-107471D01*
X311004Y-107763D01*
X312532Y-107180D01*
X314061Y-105430D01*
G01X324792Y-107763D02*
Y-96097D01*
G01Y-98430D02*
X325884Y-97263D01*
X326976Y-96388D01*
X328504Y-96097D01*
X329595Y-96388D01*
X330906Y-97263D01*
G01X342074Y-105722D02*
X343166Y-106888D01*
X344694Y-107763D01*
X346004D01*
X347314Y-107180D01*
X348187Y-106305D01*
X348624Y-105139D01*
X348406Y-103388D01*
X347532Y-102513D01*
X343602Y-100763D01*
X342729Y-98721D01*
X343166Y-97263D01*
X344039Y-96388D01*
X345349Y-96097D01*
X346659Y-96388D01*
X347969Y-97263D01*
G01X253150Y31496D02*
X344488D01*
G01X253150Y39370D02*
G03Y31496I0J-3937D01*
G01D02*
X344488D01*
G01X253150Y39370D02*
G03Y31496I0J-3937D01*
G01Y1937008D02*
X344496D01*
G01X253150D02*
G03Y1929134I0J-3937D01*
G01Y1937008D02*
X344496D01*
G01X253150D02*
G03Y1929134I0J-3937D01*
G01X356299Y0D02*
X417323D01*
G01X352362Y3937D02*
G03X356299Y0I3937J0D01*
G01X352362Y35433D02*
Y3937D01*
G01Y35433D02*
G03X348425Y39370I-3937J0D01*
G01X340551Y0D02*
G03X344488Y3937I0J3937D01*
G01Y7874D02*
Y3937D01*
G01X352362Y7874D02*
G03X344488I-3937J0D01*
G01Y31496D02*
G03X352362I3937J0D01*
G01X356299Y0D02*
X417323D01*
G01X352362Y3937D02*
G03X356299Y0I3937J0D01*
G01X352362Y35433D02*
Y3937D01*
G01Y35433D02*
G03X348425Y39370I-3937J0D01*
G01X340551Y0D02*
G03X344488Y3937I0J3937D01*
G01Y7874D02*
Y3937D01*
G01X352362Y7874D02*
G03X344488I-3937J0D01*
G01Y31496D02*
G03X352362I3937J0D01*
G01X348425Y1929134D02*
G03X352362Y1933071I0J3937D01*
G01Y1964567D02*
Y1933071D01*
G01X356299Y1968504D02*
G03X352362Y1964567I0J-3937D01*
G01X417323Y1968504D02*
X356299D01*
G01X344496Y1964567D02*
G03X340559Y1968504I-3937J0D01*
G01X344496Y1960889D02*
Y1964567D01*
G01Y1960889D02*
G03X352370I3937J0D01*
G01Y1937008D02*
G03X344496I-3937J0D01*
G01X348425Y1929134D02*
G03X352362Y1933071I0J3937D01*
G01Y1964567D02*
Y1933071D01*
G01X356299Y1968504D02*
G03X352362Y1964567I0J-3937D01*
G01X417323Y1968504D02*
X356299D01*
G01X344496Y1964567D02*
G03X340559Y1968504I-3937J0D01*
G01X344496Y1960889D02*
Y1964567D01*
G01Y1960889D02*
G03X352370I3937J0D01*
G01Y1937008D02*
G03X344496I-3937J0D01*
G01X404346Y-107763D02*
Y-90263D01*
X408712D01*
X410459Y-91138D01*
X411769Y-92305D01*
X412861Y-94054D01*
X413734Y-96097D01*
X413952Y-99013D01*
X413734Y-101930D01*
X412861Y-103972D01*
X411769Y-105722D01*
X410459Y-106888D01*
X408712Y-107763D01*
X404346D01*
G01X423374Y-99888D02*
X430361D01*
X429706Y-97846D01*
X428614Y-96680D01*
X427086Y-96097D01*
X425557Y-96388D01*
X424247Y-97263D01*
X423374Y-99305D01*
X422937Y-101055D01*
Y-102805D01*
X423374Y-104555D01*
X424466Y-106305D01*
X425776Y-107471D01*
X427304Y-107763D01*
X428832Y-107180D01*
X430361Y-105430D01*
G01X440874Y-105722D02*
X441966Y-106888D01*
X443494Y-107763D01*
X444804D01*
X446114Y-107180D01*
X446987Y-106305D01*
X447424Y-105139D01*
X447206Y-103388D01*
X446332Y-102513D01*
X442402Y-100763D01*
X441529Y-98721D01*
X441966Y-97263D01*
X442839Y-96388D01*
X444149Y-96097D01*
X445459Y-96388D01*
X446769Y-97263D01*
G01X461649Y-96097D02*
Y-107763D01*
G01Y-91430D02*
X461212Y-91138D01*
Y-90555D01*
X461649Y-90263D01*
X462086Y-90555D01*
Y-91138D01*
X461649Y-91430D01*
G01X476092Y-112138D02*
X477621Y-113305D01*
X479367Y-113596D01*
X480895Y-113305D01*
X482206Y-111847D01*
X483079Y-109805D01*
Y-96097D01*
G01Y-98430D02*
X482206Y-97263D01*
X480895Y-96388D01*
X479367Y-96097D01*
X477621Y-96680D01*
X476529Y-97846D01*
X475655Y-99888D01*
X475219Y-101930D01*
X475437Y-103680D01*
X476311Y-105722D01*
X477621Y-107180D01*
X479367Y-107763D01*
X480677Y-107471D01*
X482206Y-106305D01*
X483079Y-105139D01*
G01X492937Y-107763D02*
Y-96097D01*
G01Y-99013D02*
X493811Y-97555D01*
X495121Y-96388D01*
X496867Y-96097D01*
X498395Y-96388D01*
X499706Y-97555D01*
X500361Y-99596D01*
Y-107763D01*
G01X510874Y-99888D02*
X517861D01*
X517206Y-97846D01*
X516114Y-96680D01*
X514586Y-96097D01*
X513057Y-96388D01*
X511747Y-97263D01*
X510874Y-99305D01*
X510437Y-101055D01*
Y-102805D01*
X510874Y-104555D01*
X511966Y-106305D01*
X513276Y-107471D01*
X514804Y-107763D01*
X516332Y-107180D01*
X517861Y-105430D01*
G01X528592Y-107763D02*
Y-96097D01*
G01Y-98430D02*
X529684Y-97263D01*
X530776Y-96388D01*
X532304Y-96097D01*
X533395Y-96388D01*
X534706Y-97263D01*
G01X429134Y3937D02*
G03X433071Y0I3937J0D01*
G01X429134Y1964567D02*
Y3937D01*
G01X433071Y0D02*
X494095D01*
G01X421260Y3937D02*
Y1964567D01*
G01X417323Y0D02*
G03X421260Y3937I0J3937D01*
G01X429134Y11811D02*
G03X421260I-3937J0D01*
G01X429134Y3937D02*
G03X433071Y0I3937J0D01*
G01X429134Y1964567D02*
Y3937D01*
G01X433071Y0D02*
X494095D01*
G01X421260Y3937D02*
Y1964567D01*
G01X417323Y0D02*
G03X421260Y3937I0J3937D01*
G01X429134Y11811D02*
G03X421260I-3937J0D01*
G01Y42520D02*
G03X429134I3937J0D01*
G01X421260D02*
G03X429134I3937J0D01*
G01Y278740D02*
G03X421260I-3937J0D01*
G01X429134D02*
G03X421260I-3937J0D01*
G01Y309449D02*
G03X429134I3937J0D01*
G01X421260D02*
G03X429134I3937J0D01*
G01Y545669D02*
G03X421260I-3937J0D01*
G01X429134D02*
G03X421260I-3937J0D01*
G01Y576378D02*
G03X429134I3937J0D01*
G01X421260D02*
G03X429134I3937J0D01*
G01Y831496D02*
G03X421260I-3937J0D01*
G01X429134D02*
G03X421260I-3937J0D01*
G01Y862205D02*
G03X429134I3937J0D01*
G01X421260D02*
G03X429134I3937J0D01*
G01Y1106299D02*
G03X421260I-3937J0D01*
G01X429134D02*
G03X421260I-3937J0D01*
G01Y1137008D02*
G03X429134I3937J0D01*
G01X421260D02*
G03X429134I3937J0D01*
G01Y1392126D02*
G03X421260I-3937J0D01*
G01X429134D02*
G03X421260I-3937J0D01*
G01Y1422835D02*
G03X429134I3937J0D01*
G01X421260D02*
G03X429134I3937J0D01*
G01Y1659055D02*
G03X421260I-3937J0D01*
G01X429134D02*
G03X421260I-3937J0D01*
G01Y1689764D02*
G03X429134I3937J0D01*
G01X421260D02*
G03X429134I3937J0D01*
G01Y1925984D02*
G03X421260I-3937J0D01*
G01X429134D02*
G03X421260I-3937J0D01*
G01X433071Y1968504D02*
G03X429134Y1964567I0J-3937D01*
G01X494095Y1968504D02*
X433071D01*
G01X421260Y1964567D02*
G03X417323Y1968504I-3937J0D01*
G01X421260Y1956693D02*
G03X429134I3937J0D01*
G01X433071Y1968504D02*
G03X429134Y1964567I0J-3937D01*
G01X494095Y1968504D02*
X433071D01*
G01X421260Y1964567D02*
G03X417323Y1968504I-3937J0D01*
G01X421260Y1956693D02*
G03X429134I3937J0D01*
G01X433071Y1968504D02*
G03X429134Y1964567I0J-3937D01*
G01X421260D02*
G03X417323Y1968504I-3937J0D01*
G01X448096Y-152763D02*
Y-135263D01*
X452462D01*
X454209Y-136138D01*
X455519Y-137305D01*
X456611Y-139054D01*
X457484Y-141097D01*
X457702Y-144013D01*
X457484Y-146930D01*
X456611Y-148972D01*
X455519Y-150722D01*
X454209Y-151888D01*
X452462Y-152763D01*
X448096D01*
G01X470399Y-141097D02*
Y-152763D01*
G01Y-136430D02*
X469962Y-136138D01*
Y-135555D01*
X470399Y-135263D01*
X470836Y-135555D01*
Y-136138D01*
X470399Y-136430D01*
G01X487899Y-152763D02*
X486589Y-152471D01*
X485279Y-151305D01*
X484405Y-149263D01*
X483969Y-146930D01*
X484405Y-144596D01*
X485279Y-142555D01*
X486589Y-141388D01*
X487899Y-141097D01*
X489209Y-141388D01*
X490519Y-142555D01*
X491392Y-144596D01*
X491611Y-146930D01*
X491392Y-149263D01*
X490519Y-151305D01*
X489209Y-152471D01*
X487899Y-152763D01*
G01X501969Y39370D02*
G03X498032Y35433I0J-3937D01*
G01Y3937D02*
Y35433D01*
G01X494095Y0D02*
G03X498032Y3937I0J3937D01*
G01X505897Y0D02*
X648386D01*
G01X505897Y7615D02*
Y0D01*
G01X597244Y31496D02*
X505897D01*
G01Y7615D02*
G03X498023I-3937J0D01*
G01Y31496D02*
G03X505897I3937J0D01*
G01X501969Y39370D02*
G03X498032Y35433I0J-3937D01*
G01Y3937D02*
Y35433D01*
G01X494095Y0D02*
G03X498032Y3937I0J3937D01*
G01X505897Y0D02*
X620827D01*
G01X505897Y7615D02*
Y0D01*
G01X597244Y31496D02*
X505897D01*
G01Y7615D02*
G03X498023I-3937J0D01*
G01Y31496D02*
G03X505897I3937J0D01*
G01X501969Y39370D02*
X631890D01*
G01X501969D02*
X631890D01*
G01X498032Y1964567D02*
G03X494095Y1968504I-3937J0D01*
G01X498032Y1933071D02*
Y1960630D01*
G01Y1933071D02*
G03X501969Y1929134I3937J0D01*
G01X631890D02*
X501969D01*
G01X505906Y1960630D02*
Y1968504D01*
G01D02*
X648386D01*
G01X597244Y1937008D02*
X505906D01*
G01X498032Y1960630D02*
G03X505906I3937J0D01*
G01Y1937008D02*
G03X498032I-3937J0D01*
G01Y1964567D02*
G03X494095Y1968504I-3937J0D01*
G01X498032Y1933071D02*
Y1964567D01*
G01Y1933071D02*
G03X501969Y1929134I3937J0D01*
G01X631890D02*
X501969D01*
G01X505906Y1960630D02*
Y1968504D01*
G01D02*
X620827D01*
G01X597244Y1937008D02*
X505906D01*
G01X498032Y1960630D02*
G03X505906I3937J0D01*
G01Y1937008D02*
G03X498032I-3937J0D01*
G01X575349Y-152763D02*
Y-135263D01*
X572729Y-138763D01*
G01Y-152763D02*
X577969D01*
G01X588701Y-138180D02*
X590011Y-136430D01*
X591539Y-135555D01*
X593286Y-135263D01*
X595469Y-135846D01*
X596997Y-137305D01*
X597434Y-139054D01*
X597216Y-140805D01*
X596342Y-142263D01*
X591976Y-145180D01*
X590011Y-147221D01*
X588701Y-150139D01*
X588264Y-152763D01*
X597434D01*
G01X606419Y-153346D02*
X614279Y-135263D01*
G01X627849D02*
X626102Y-135846D01*
X624792Y-137305D01*
X623919Y-139054D01*
X623264Y-141388D01*
X623046Y-144013D01*
X623264Y-146638D01*
X623919Y-148972D01*
X624792Y-150722D01*
X626102Y-152180D01*
X627849Y-152763D01*
X629595Y-152180D01*
X630906Y-150722D01*
X631779Y-148972D01*
X632434Y-146638D01*
X632652Y-144013D01*
X632434Y-141388D01*
X631779Y-139054D01*
X630906Y-137305D01*
X629595Y-135846D01*
X627849Y-135263D01*
G01X644912Y-152763D02*
X645349Y-148972D01*
X646004Y-145763D01*
X646877Y-142846D01*
X647969Y-139638D01*
X649716Y-135263D01*
X640982D01*
G01X658919Y-153346D02*
X666779Y-135263D01*
G01X676201Y-138180D02*
X677511Y-136430D01*
X679039Y-135555D01*
X680786Y-135263D01*
X682969Y-135846D01*
X684497Y-137305D01*
X684934Y-139054D01*
X684716Y-140805D01*
X683842Y-142263D01*
X679476Y-145180D01*
X677511Y-147221D01*
X676201Y-150139D01*
X675764Y-152763D01*
X684934D01*
G01X697849Y-135263D02*
X696102Y-135846D01*
X694792Y-137305D01*
X693919Y-139054D01*
X693264Y-141388D01*
X693046Y-144013D01*
X693264Y-146638D01*
X693919Y-148972D01*
X694792Y-150722D01*
X696102Y-152180D01*
X697849Y-152763D01*
X699595Y-152180D01*
X700906Y-150722D01*
X701779Y-148972D01*
X702434Y-146638D01*
X702652Y-144013D01*
X702434Y-141388D01*
X701779Y-139054D01*
X700906Y-137305D01*
X699595Y-135846D01*
X697849Y-135263D01*
G01X715349Y-152763D02*
Y-135263D01*
X712729Y-138763D01*
G01Y-152763D02*
X717969D01*
G01X728701Y-138180D02*
X730011Y-136430D01*
X731539Y-135555D01*
X733286Y-135263D01*
X735469Y-135846D01*
X736997Y-137305D01*
X737434Y-139054D01*
X737216Y-140805D01*
X736342Y-142263D01*
X731976Y-145180D01*
X730011Y-147221D01*
X728701Y-150139D01*
X728264Y-152763D01*
X737434D01*
G01X623046Y-107763D02*
Y-90263D01*
X627412D01*
X629159Y-91138D01*
X630469Y-92305D01*
X631561Y-94054D01*
X632434Y-96097D01*
X632652Y-99013D01*
X632434Y-101930D01*
X631561Y-103972D01*
X630469Y-105722D01*
X629159Y-106888D01*
X627412Y-107763D01*
X623046D01*
G01X649279D02*
Y-96097D01*
G01Y-98138D02*
X648406Y-96972D01*
X647095Y-96388D01*
X645567Y-96097D01*
X644039Y-96680D01*
X642729Y-97846D01*
X641855Y-99596D01*
X641419Y-101930D01*
X641855Y-104263D01*
X642729Y-106013D01*
X644039Y-107180D01*
X645567Y-107763D01*
X647095Y-107471D01*
X648406Y-106597D01*
X649279Y-105430D01*
G01X662849Y-90263D02*
Y-107763D01*
G01X659792Y-96097D02*
X665906D01*
G01X677074Y-99888D02*
X684061D01*
X683406Y-97846D01*
X682314Y-96680D01*
X680786Y-96097D01*
X679257Y-96388D01*
X677947Y-97263D01*
X677074Y-99305D01*
X676637Y-101055D01*
Y-102805D01*
X677074Y-104555D01*
X678166Y-106305D01*
X679476Y-107471D01*
X681004Y-107763D01*
X682532Y-107180D01*
X684061Y-105430D01*
G01X635827Y31496D02*
G03X643701Y39370I0J7874D01*
G01X650689Y19685D02*
G03I-6988J0D01*
G01X635827Y31496D02*
X627953D01*
G01X597244D02*
G03Y39370I0J3937D01*
G01X627953D02*
G03Y31496I0J-3937D01*
G01X650689Y19685D02*
G03I-6988J0D01*
G01X635827Y31496D02*
X627953D01*
G01X597244D02*
G03Y39370I0J3937D01*
G01X627953D02*
G03Y31496I0J-3937D01*
G01X635827Y161417D02*
Y43307D01*
G01X631890Y39370D02*
G03X635827Y43307I0J3937D01*
G01X631890Y39370D02*
G03X635827Y43307I0J3937D01*
G01X643701Y169256D02*
G03X635827I-3937J0D01*
G01X643701D02*
G03X635827I-3937J0D01*
G01Y161417D02*
Y1807087D01*
G01Y161417D02*
Y1807087D01*
G01Y199965D02*
G03X643701I3937J0D01*
G01X635827D02*
G03X643701I3937J0D01*
G01Y436186D02*
G03X635827I-3937J0D01*
G01X643701D02*
G03X635827I-3937J0D01*
G01Y466894D02*
G03X643701I3937J0D01*
G01X635827D02*
G03X643701I3937J0D01*
G01Y703115D02*
G03X635827I-3937J0D01*
G01Y733823D02*
G03X643701I3937J0D01*
G01Y703115D02*
G03X635827I-3937J0D01*
G01Y733823D02*
G03X643701I3937J0D01*
G01X635827Y997603D02*
G03X643701I3937J0D01*
G01Y970832D02*
G03X635827I-3937J0D01*
G01Y997603D02*
G03X643701I3937J0D01*
G01Y970832D02*
G03X635827I-3937J0D01*
G01Y1265320D02*
G03X643701I3937J0D01*
G01Y1234611D02*
G03X635827I-3937J0D01*
G01Y1265320D02*
G03X643701I3937J0D01*
G01Y1234611D02*
G03X635827I-3937J0D01*
G01X643701Y1501541D02*
G03X635827I-3937J0D01*
G01X643701D02*
G03X635827I-3937J0D01*
G01Y1532249D02*
G03X643701I3937J0D01*
G01X635827D02*
G03X643701I3937J0D01*
G01Y1768470D02*
G03X635827I-3937J0D01*
G01X643701D02*
G03X635827I-3937J0D01*
G01Y1799178D02*
G03X643701I3937J0D01*
G01X635827D02*
G03X643701I3937J0D01*
G01X635827Y1818898D02*
Y1807087D01*
G01Y1818898D02*
Y1925197D01*
G01Y1818898D02*
Y1925197D01*
G01D02*
G03X631890Y1929134I-3937J0D01*
G01X635827Y1925197D02*
G03X631890Y1929134I-3937J0D01*
G01X643701D02*
G03X635827Y1937008I-7874J0D01*
G01X650689Y1948819D02*
G03I-6988J0D01*
G01X627953Y1937008D02*
X635827D01*
G01X627953D02*
G03Y1929134I0J-3937D01*
G01X597244D02*
G03Y1937008I0J3937D01*
G01X650689Y1948819D02*
G03I-6988J0D01*
G01X627953Y1937008D02*
X635827D01*
G01X627953D02*
G03Y1929134I0J-3937D01*
G01X597244D02*
G03Y1937008I0J3937D01*
G01X650689Y1948819D02*
G03I-6988J0D01*
G01X648386Y0D02*
G03X663386Y15000I0J15000D01*
G01Y1953504D02*
Y15000D01*
G01X643701Y169256D02*
Y39370D01*
G01Y436186D02*
Y199965D01*
G01Y703115D02*
Y466894D01*
G01Y970832D02*
Y733823D01*
G01Y1234611D02*
Y997603D01*
G01Y1501541D02*
Y1265320D01*
G01Y1768470D02*
Y1532249D01*
G01Y1929134D02*
Y1799178D01*
G01X663386Y1953504D02*
G03X648386Y1968504I-15000J0D01*
G54D47*
X49900Y883800D03*
Y894800D03*
X63800Y986600D03*
Y975600D03*
X39000Y1022500D03*
Y1033500D03*
X96000Y931000D03*
Y942000D03*
X147000Y732000D03*
Y721000D03*
G54D65*
X111882Y1461600D03*
X114441D03*
X117000D03*
X119559D03*
X122118D03*
Y1442400D03*
X119559D03*
X117000D03*
X114441D03*
X111882D03*
G36*
G01X96467Y1729085D02*
G03X96447I-10J18750D01*
G01Y1737885D01*
G02X96467I10J9950D01*
G01Y1729085D01*
G37*
G36*
G01Y1804281D02*
G03X96447I-10J18750D01*
G01Y1813081D01*
G02X96467I10J9950D01*
G01Y1804281D01*
G37*
G36*
G01X178947Y1309990D02*
G03X178927I-10J18750D01*
G01Y1318790D01*
G02X178947I10J9950D01*
G01Y1309990D01*
G37*
G36*
G01X161427Y1729085D02*
G03X161407I-10J18750D01*
G01Y1737885D01*
G02X161427I10J9950D01*
G01Y1729085D01*
G37*
G36*
G01Y1804281D02*
G03X161407I-10J18750D01*
G01Y1813081D01*
G02X161427I10J9950D01*
G01Y1804281D01*
G37*
G54D29*
X72200Y86200D03*
X72602Y757897D03*
X63700Y1050100D03*
X99000Y86200D03*
X99402Y757897D03*
X90500Y1050100D03*
G54D38*
X56200Y252800D03*
X40000Y294300D03*
X73500Y591000D03*
X76600Y986600D03*
X67600Y1025000D03*
X83847Y61398D03*
X116900Y380100D03*
X91529Y533679D03*
X107100Y986000D03*
Y990800D03*
X94800Y1455500D03*
X106800Y1474500D03*
X165900Y532100D03*
X165700Y553300D03*
X182021Y613535D03*
X160300Y1462500D03*
G54D48*
X63901Y949600D03*
X86699D03*
G54D66*
X126600Y1457118D03*
Y1454559D03*
Y1452000D03*
Y1449441D03*
Y1446882D03*
X107400D03*
Y1449441D03*
Y1452000D03*
Y1454559D03*
Y1457118D03*
G54D57*
X89335Y544750D03*
X87370D03*
X85400D03*
X83430D03*
X81465D03*
Y561050D03*
X83430D03*
X85400D03*
X87370D03*
X89335D03*
X108710Y612629D03*
X110675D03*
X112645D03*
X114615D03*
X116580D03*
X118550D03*
X120520D03*
X122490D03*
X124455D03*
X126425D03*
X128395D03*
X130360D03*
Y646029D03*
X128395D03*
X126425D03*
X124455D03*
X122490D03*
X120520D03*
X118550D03*
X116580D03*
X114615D03*
X112645D03*
X110675D03*
X108710D03*
X153135Y542950D03*
X151170D03*
X149200D03*
X147230D03*
X145265D03*
Y559250D03*
X147230D03*
X149200D03*
X151170D03*
X153135D03*
G54D39*
X69635Y361900D03*
X110735Y361800D03*
X99365Y361900D03*
X140465Y361800D03*
X157835Y1507700D03*
X187565D03*
G54D67*
X117000Y1452000D03*
G54D58*
X102835Y640154D03*
Y638189D03*
Y636219D03*
Y634249D03*
Y632284D03*
Y630314D03*
Y628344D03*
Y626374D03*
Y624409D03*
Y622439D03*
Y620469D03*
Y618504D03*
X136235D03*
Y620469D03*
Y622439D03*
Y624409D03*
Y626374D03*
Y628344D03*
Y630314D03*
Y632284D03*
Y634249D03*
Y636219D03*
Y638189D03*
Y640154D03*
G54D49*
X77400Y980050D03*
Y976300D03*
Y972550D03*
X88000D03*
Y976300D03*
Y980050D03*
G54D59*
X89435Y642629D03*
Y635029D03*
X89500Y1461700D03*
Y1469300D03*
X172100Y549100D03*
Y541500D03*
X170100Y607600D03*
Y615200D03*
X152265Y608971D03*
Y601371D03*
X167000Y1457700D03*
Y1465300D03*
G54D68*
X171370Y634819D03*
X159800D03*
X171370Y645839D03*
X159800D03*
G54D69*
X180465Y631371D03*
Y634971D03*
M02*
